FILE_TYPE = MACRO_DRAWING;
SET COLOR_WIRE YELLOW;
SET COLOR_PROP ORANGE;
SET COLOR_DOT WHITE;
SET COLOR_ARC YELLOW;
SET COLOR_BODY GREEN;
SET COLOR_NOTE PURPLE;
SET PROP_DISPLAY VALUE;
SET PAGE_NUMBER P35;
SET PATH_NUMBER P154;
FORCEADD LCMXO3LF2100C5BG256C..2
(-4750 3875);
FORCEPROP 1 LAST PART_NUMBER AJ021000T03
J 0
(-5470 5391);
DISPLAY 0.723404 (-5470 5391);
PAINT GREEN (-5470 5391);
FORCEPROP 2 LAST VALUE LCMXO3LF-2100C-5BG256C
J 0
(-5450 5525);
DISPLAY 0.680851 (-5450 5525);
FORCEPROP 1 LAST MATERIAL IC
J 0
(-5470 5312);
DISPLAY 0.723404 (-5470 5312);
PAINT GREEN (-5470 5312);
FORCEPROP 2 LAST PART_TYPE SMLF
J 0
(-5450 5575);
DISPLAY 0.680851 (-5450 5575);
FORCEPROP 1 LAST CDS_LMAN_SYM_OUTLINE -725,1425,725,-1425
J 0
(-4750 3875);
DISPLAY 0.468085 (-4750 3875);
PAINT GREEN (-4750 3875);
DISPLAY INVISIBLE (-4750 3875);
FORCEPROP 1 LAST NEEDS_NO_SIZE TRUE
J 0
(-4750 3875);
DISPLAY 0.723404 (-4750 3875);
PAINT GREEN (-4750 3875);
DISPLAY INVISIBLE (-4750 3875);
FORCEPROP 1 LAST PATH I1
J 0
(-4750 3875);
DISPLAY 0.723404 (-4750 3875);
PAINT GREEN (-4750 3875);
DISPLAY INVISIBLE (-4750 3875);
FORCEPROP 2 LAST CDS_LIB pure_quanta
J 0
(-4750 3875);
DISPLAY INVISIBLE (-4750 3875);
FORCEPROP 1 LAST LOCATION U25
J 0
(-5470 5478);
DISPLAY 0.723404 (-5470 5478);
PAINT GREEN (-5470 5478);
FORCEPROP 0 LASTPIN (-3875 5100) $PN D14
J 0
(-3865 5110);
DISPLAY 0.680851 (-3865 5110);
PAINT MONO (-3865 5110);
FORCEPROP 0 LASTPIN (-3875 5050) $PN E15
J 0
(-3865 5060);
DISPLAY 0.680851 (-3865 5060);
PAINT MONO (-3865 5060);
FORCEPROP 0 LASTPIN (-5625 5100) $PN C15
J 2
(-5635 5110);
DISPLAY 0.680851 (-5635 5110);
PAINT MONO (-5635 5110);
FORCEPROP 0 LASTPIN (-5625 5050) $PN B16
J 2
(-5635 5060);
DISPLAY 0.680851 (-5635 5060);
PAINT MONO (-5635 5060);
FORCEPROP 0 LASTPIN (-3875 4950) $PN D16
J 0
(-3865 4960);
DISPLAY 0.680851 (-3865 4960);
PAINT MONO (-3865 4960);
FORCEPROP 0 LASTPIN (-3875 4900) $PN E14
J 0
(-3865 4910);
DISPLAY 0.680851 (-3865 4910);
PAINT MONO (-3865 4910);
FORCEPROP 0 LASTPIN (-5625 4950) $PN C16
J 2
(-5635 4960);
DISPLAY 0.680851 (-5635 4960);
PAINT MONO (-5635 4960);
FORCEPROP 0 LASTPIN (-5625 4900) $PN D15
J 2
(-5635 4910);
DISPLAY 0.680851 (-5635 4910);
PAINT MONO (-5635 4910);
FORCEPROP 0 LASTPIN (-3875 4800) $PN E16
J 0
(-3865 4810);
DISPLAY 0.680851 (-3865 4810);
PAINT MONO (-3865 4810);
FORCEPROP 0 LASTPIN (-3875 4750) $PN F15
J 0
(-3865 4760);
DISPLAY 0.680851 (-3865 4760);
PAINT MONO (-3865 4760);
FORCEPROP 0 LASTPIN (-5625 4800) $PN F13
J 2
(-5635 4810);
DISPLAY 0.680851 (-5635 4810);
PAINT MONO (-5635 4810);
FORCEPROP 0 LASTPIN (-5625 4750) $PN G12
J 2
(-5635 4760);
DISPLAY 0.680851 (-5635 4760);
PAINT MONO (-5635 4760);
FORCEPROP 0 LASTPIN (-3875 4650) $PN F14
J 0
(-3865 4660);
DISPLAY 0.680851 (-3865 4660);
PAINT MONO (-3865 4660);
FORCEPROP 0 LASTPIN (-3875 4600) $PN F16
J 0
(-3865 4610);
DISPLAY 0.680851 (-3865 4610);
PAINT MONO (-3865 4610);
FORCEPROP 0 LASTPIN (-5625 4650) $PN F12
J 2
(-5635 4660);
DISPLAY 0.680851 (-5635 4660);
PAINT MONO (-5635 4660);
FORCEPROP 0 LASTPIN (-5625 4600) $PN G13
J 2
(-5635 4610);
DISPLAY 0.680851 (-5635 4610);
PAINT MONO (-5635 4610);
FORCEPROP 0 LASTPIN (-3875 4500) $PN G15
J 0
(-3865 4510);
DISPLAY 0.680851 (-3865 4510);
PAINT MONO (-3865 4510);
FORCEPROP 0 LASTPIN (-3875 4450) $PN G14
J 0
(-3865 4460);
DISPLAY 0.680851 (-3865 4460);
PAINT MONO (-3865 4460);
FORCEPROP 0 LASTPIN (-5625 4500) $PN G11
J 2
(-5635 4510);
DISPLAY 0.680851 (-5635 4510);
PAINT MONO (-5635 4510);
FORCEPROP 0 LASTPIN (-5625 4450) $PN H12
J 2
(-5635 4460);
DISPLAY 0.680851 (-5635 4460);
PAINT MONO (-5635 4460);
FORCEPROP 0 LASTPIN (-3875 4350) $PN G16
J 0
(-3865 4360);
DISPLAY 0.680851 (-3865 4360);
PAINT MONO (-3865 4360);
FORCEPROP 0 LASTPIN (-3875 4300) $PN H15
J 0
(-3865 4310);
DISPLAY 0.680851 (-3865 4310);
PAINT MONO (-3865 4310);
FORCEPROP 0 LASTPIN (-5625 4350) $PN H13
J 2
(-5635 4360);
DISPLAY 0.680851 (-5635 4360);
PAINT MONO (-5635 4360);
FORCEPROP 0 LASTPIN (-5625 4300) $PN J12
J 2
(-5635 4310);
DISPLAY 0.680851 (-5635 4310);
PAINT MONO (-5635 4310);
FORCEPROP 0 LASTPIN (-3875 4200) $PN H14
J 0
(-3865 4210);
DISPLAY 0.680851 (-3865 4210);
PAINT MONO (-3865 4210);
FORCEPROP 0 LASTPIN (-3875 4150) $PN H16
J 0
(-3865 4160);
DISPLAY 0.680851 (-3865 4160);
PAINT MONO (-3865 4160);
FORCEPROP 0 LASTPIN (-5625 4200) $PN J16
J 2
(-5635 4210);
DISPLAY 0.680851 (-5635 4210);
PAINT MONO (-5635 4210);
FORCEPROP 0 LASTPIN (-5625 4150) $PN J14
J 2
(-5635 4160);
DISPLAY 0.680851 (-5635 4160);
PAINT MONO (-5635 4160);
FORCEPROP 0 LASTPIN (-3875 4000) $PN J15
J 0
(-3865 4010);
DISPLAY 0.680851 (-3865 4010);
PAINT MONO (-3865 4010);
FORCEPROP 0 LASTPIN (-3875 3950) $PN K16
J 0
(-3865 3960);
DISPLAY 0.680851 (-3865 3960);
PAINT MONO (-3865 3960);
FORCEPROP 0 LASTPIN (-5625 4050) $PN H11
J 2
(-5635 4060);
DISPLAY 0.680851 (-5635 4060);
PAINT MONO (-5635 4060);
FORCEPROP 0 LASTPIN (-5625 4000) $PN J13
J 2
(-5635 4010);
DISPLAY 0.680851 (-5635 4010);
PAINT MONO (-5635 4010);
FORCEPROP 0 LASTPIN (-3875 3850) $PN K14
J 0
(-3865 3860);
DISPLAY 0.680851 (-3865 3860);
PAINT MONO (-3865 3860);
FORCEPROP 0 LASTPIN (-3875 3800) $PN K15
J 0
(-3865 3810);
DISPLAY 0.680851 (-3865 3810);
PAINT MONO (-3865 3810);
FORCEPROP 0 LASTPIN (-5625 3900) $PN J11
J 2
(-5635 3910);
DISPLAY 0.680851 (-5635 3910);
PAINT MONO (-5635 3910);
FORCEPROP 0 LASTPIN (-5625 3850) $PN L12
J 2
(-5635 3860);
DISPLAY 0.680851 (-5635 3860);
PAINT MONO (-5635 3860);
FORCEPROP 0 LASTPIN (-3875 3700) $PN L16
J 0
(-3865 3710);
DISPLAY 0.680851 (-3865 3710);
PAINT MONO (-3865 3710);
FORCEPROP 0 LASTPIN (-3875 3650) $PN L14
J 0
(-3865 3660);
DISPLAY 0.680851 (-3865 3660);
PAINT MONO (-3865 3660);
FORCEPROP 0 LASTPIN (-3875 3550) $PN K13
J 0
(-3865 3560);
DISPLAY 0.680851 (-3865 3560);
PAINT MONO (-3865 3560);
FORCEPROP 0 LASTPIN (-3875 3500) $PN K12
J 0
(-3865 3510);
DISPLAY 0.680851 (-3865 3510);
PAINT MONO (-3865 3510);
FORCEPROP 0 LASTPIN (-3875 3400) $PN L15
J 0
(-3865 3410);
DISPLAY 0.680851 (-3865 3410);
PAINT MONO (-3865 3410);
FORCEPROP 0 LASTPIN (-3875 3350) $PN M16
J 0
(-3865 3360);
DISPLAY 0.680851 (-3865 3360);
PAINT MONO (-3865 3360);
FORCEPROP 0 LASTPIN (-5625 3750) $PN K11
J 2
(-5635 3760);
DISPLAY 0.680851 (-5635 3760);
PAINT MONO (-5635 3760);
FORCEPROP 0 LASTPIN (-5625 3700) $PN L13
J 2
(-5635 3710);
DISPLAY 0.680851 (-5635 3710);
PAINT MONO (-5635 3710);
FORCEPROP 0 LASTPIN (-3875 3250) $PN M14
J 0
(-3865 3260);
DISPLAY 0.680851 (-3865 3260);
PAINT MONO (-3865 3260);
FORCEPROP 0 LASTPIN (-3875 3200) $PN M15
J 0
(-3865 3210);
DISPLAY 0.680851 (-3865 3210);
PAINT MONO (-3865 3210);
FORCEPROP 0 LASTPIN (-5625 3600) $PN N15
J 2
(-5635 3610);
DISPLAY 0.680851 (-5635 3610);
PAINT MONO (-5635 3610);
FORCEPROP 0 LASTPIN (-5625 3550) $PN P16
J 2
(-5635 3560);
DISPLAY 0.680851 (-5635 3560);
PAINT MONO (-5635 3560);
FORCEPROP 0 LASTPIN (-3875 3100) $PN N16
J 0
(-3865 3110);
DISPLAY 0.680851 (-3865 3110);
PAINT MONO (-3865 3110);
FORCEPROP 0 LASTPIN (-3875 3050) $PN N14
J 0
(-3865 3060);
DISPLAY 0.680851 (-3865 3060);
PAINT MONO (-3865 3060);
FORCEPROP 0 LASTPIN (-5625 3450) $PN P15
J 2
(-5635 3460);
DISPLAY 0.680851 (-5635 3460);
PAINT MONO (-5635 3460);
FORCEPROP 0 LASTPIN (-5625 3400) $PN R16
J 2
(-5635 3410);
DISPLAY 0.680851 (-5635 3410);
PAINT MONO (-5635 3410);
FORCEPROP 0 LASTPIN (-5625 2650) $PN E13
J 2
(-5635 2660);
DISPLAY 0.680851 (-5635 2660);
PAINT MONO (-5635 2660);
FORCEPROP 0 LASTPIN (-5625 2600) $PN H10
J 2
(-5635 2610);
DISPLAY 0.680851 (-5635 2610);
PAINT MONO (-5635 2610);
FORCEPROP 0 LASTPIN (-3875 2650) $PN J10
J 0
(-3865 2660);
DISPLAY 0.680851 (-3865 2660);
PAINT MONO (-3865 2660);
FORCEPROP 0 LASTPIN (-3875 2600) $PN M13
J 0
(-3865 2610);
DISPLAY 0.680851 (-3865 2610);
PAINT MONO (-3865 2610);
FORCEPROP 0 LAST $SEC 2
J 0
(-5450 5625);
DISPLAY 0.680851 (-5450 5625);
PAINT MONO (-5450 5625);
DISPLAY INVISIBLE (-5450 5625);
FORCEPROP 0 LAST CDS_SEC 2
J 0
(-5450 5625);
DISPLAY 0.680851 (-5450 5625);
DISPLAY INVISIBLE (-5450 5625);
FORCEADD OFFPAGE..6
(-8550 4800);
FORCEPROP 2 LAST $XR0 15 
J 0
(-8829 4800);
DISPLAY 0.638298 (-8829 4800);
PAINT MONO (-8829 4800);
FORCEPROP 2 LAST $XR1 27 
J 0
(-8919 4800);
DISPLAY 0.638298 (-8919 4800);
PAINT MONO (-8919 4800);
FORCEPROP 2 LAST PATH I10
J 0
(-8775 4850);
DISPLAY 0.680851 (-8775 4850);
DISPLAY INVISIBLE (-8775 4850);
FORCEPROP 2 LAST CDS_LIB standard
J 0
(-8550 4800);
DISPLAY INVISIBLE (-8550 4800);
FORCEPROP 1 LAST OFFPAGE TRUE
J 0
(-8225 4675);
DISPLAY 0.872340 (-8225 4675);
DISPLAY INVISIBLE (-8225 4675);
FORCEPROP 1 LAST COMMENT_BODY TRUE
J 0
(-8450 4725);
DISPLAY 0.872340 (-8450 4725);
PAINT GREEN (-8450 4725);
DISPLAY INVISIBLE (-8450 4725);
FORCEADD Q_RES..1
(-1800 3850);
FORCEPROP 1 LAST VALUE 0
J 2
(-1650 3850);
DISPLAY 0.510638 (-1650 3850);
PAINT SKYBLUE (-1650 3850);
FORCEPROP 1 LAST MATERIAL CHIP
J 2
(-1475 3850);
DISPLAY 0.510638 (-1475 3850);
PAINT SKYBLUE (-1475 3850);
FORCEPROP 1 LAST PART_NUMBER CS00002JB13
J 0
(-1900 3925);
DISPLAY 0.510638 (-1900 3925);
PAINT WHITE (-1900 3925);
DISPLAY INVISIBLE (-1900 3925);
FORCEPROP 1 LAST PACK_TYPE 0402LF
J 0
(-1825 3900);
DISPLAY 0.510638 (-1825 3900);
PAINT SKYBLUE (-1825 3900);
DISPLAY INVISIBLE (-1825 3900);
FORCEPROP 1 LAST WATTAGE 1/16W
J 2
(-1450 3950);
DISPLAY 0.510638 (-1450 3950);
PAINT SKYBLUE (-1450 3950);
DISPLAY INVISIBLE (-1450 3950);
FORCEPROP 1 LAST TOLERANCE 5%
J 0
(-1875 3950);
DISPLAY 0.510638 (-1875 3950);
PAINT SKYBLUE (-1875 3950);
DISPLAY INVISIBLE (-1875 3950);
FORCEPROP 2 LAST CDS_LIB pure_quanta
J 0
(-1800 3850);
DISPLAY INVISIBLE (-1800 3850);
FORCEPROP 2 LAST SEC_TYPE 0402LF
J 0
(-1850 4050);
DISPLAY 0.680851 (-1850 4050);
DISPLAY INVISIBLE (-1850 4050);
FORCEPROP 1 LAST PATH I100
J 0
(-1850 4000);
DISPLAY 0.978723 (-1850 4000);
PAINT WHITE (-1850 4000);
DISPLAY INVISIBLE (-1850 4000);
FORCEPROP 1 LAST LOCATION R432
J 0
(-2075 3850);
DISPLAY 0.702128 (-2075 3850);
PAINT YELLOW (-2075 3850);
FORCEPROP 1 LASTPIN (-1900 3850) $PN 1
J 0
(-1888 3862);
DISPLAY 0.808511 (-1888 3862);
PAINT WHITE (-1888 3862);
FORCEPROP 1 LASTPIN (-1700 3850) $PN 2
J 0
(-1738 3862);
DISPLAY 0.808511 (-1738 3862);
PAINT WHITE (-1738 3862);
FORCEPROP 0 LAST SEC 1
J 0
(-1950 3900);
DISPLAY 0.680851 (-1950 3900);
PAINT MONO (-1950 3900);
DISPLAY INVISIBLE (-1950 3900);
FORCEADD OFFPAGE..4
(-750 3050);
FORCEPROP 2 LAST $XR0 53 
J 0
(-564 3050);
DISPLAY 0.638298 (-564 3050);
PAINT MONO (-564 3050);
FORCEPROP 2 LAST PATH I106
J 0
(-450 3100);
DISPLAY 0.680851 (-450 3100);
DISPLAY INVISIBLE (-450 3100);
FORCEPROP 2 LAST CDS_LIB standard
J 0
(-750 3050);
DISPLAY INVISIBLE (-750 3050);
FORCEPROP 1 LAST OFFPAGE TRUE
J 0
(-425 2925);
DISPLAY 0.872340 (-425 2925);
PAINT GREEN (-425 2925);
DISPLAY INVISIBLE (-425 2925);
FORCEPROP 1 LAST COMMENT_BODY TRUE
J 0
(-775 2950);
DISPLAY 0.872340 (-775 2950);
PAINT PEACH (-775 2950);
DISPLAY INVISIBLE (-775 2950);
FORCEADD OFFPAGE..4
(-750 3200);
FORCEPROP 2 LAST $XR2 54 
J 0
(-384 3200);
DISPLAY 0.638298 (-384 3200);
PAINT MONO (-384 3200);
FORCEPROP 2 LAST $XR4 56 
J 0
(-204 3200);
DISPLAY 0.638298 (-204 3200);
PAINT MONO (-204 3200);
FORCEPROP 2 LAST $XR0 51 
J 0
(-564 3200);
DISPLAY 0.638298 (-564 3200);
PAINT MONO (-564 3200);
FORCEPROP 2 LAST $XR1 52 
J 0
(-474 3200);
DISPLAY 0.638298 (-474 3200);
PAINT MONO (-474 3200);
FORCEPROP 2 LAST $XR3 55 
J 0
(-294 3200);
DISPLAY 0.638298 (-294 3200);
PAINT MONO (-294 3200);
FORCEPROP 2 LAST PATH I109
J 0
(-450 3250);
DISPLAY 0.680851 (-450 3250);
DISPLAY INVISIBLE (-450 3250);
FORCEPROP 2 LAST CDS_LIB standard
J 0
(-750 3200);
DISPLAY INVISIBLE (-750 3200);
FORCEPROP 1 LAST OFFPAGE TRUE
J 0
(-425 3075);
DISPLAY 0.872340 (-425 3075);
PAINT GREEN (-425 3075);
DISPLAY INVISIBLE (-425 3075);
FORCEPROP 1 LAST COMMENT_BODY TRUE
J 0
(-775 3100);
DISPLAY 0.872340 (-775 3100);
PAINT PEACH (-775 3100);
DISPLAY INVISIBLE (-775 3100);
FORCEADD OFFPAGE..6
(-8550 4750);
FORCEPROP 2 LAST $XR0 15 
J 0
(-8829 4750);
DISPLAY 0.638298 (-8829 4750);
PAINT MONO (-8829 4750);
FORCEPROP 2 LAST $XR1 27 
J 0
(-8919 4750);
DISPLAY 0.638298 (-8919 4750);
PAINT MONO (-8919 4750);
FORCEPROP 2 LAST PATH I11
J 0
(-8775 4800);
DISPLAY 0.680851 (-8775 4800);
DISPLAY INVISIBLE (-8775 4800);
FORCEPROP 2 LAST CDS_LIB standard
J 0
(-8550 4750);
DISPLAY INVISIBLE (-8550 4750);
FORCEPROP 1 LAST OFFPAGE TRUE
J 0
(-8225 4625);
DISPLAY 0.872340 (-8225 4625);
DISPLAY INVISIBLE (-8225 4625);
FORCEPROP 1 LAST COMMENT_BODY TRUE
J 0
(-8450 4675);
DISPLAY 0.872340 (-8450 4675);
PAINT GREEN (-8450 4675);
DISPLAY INVISIBLE (-8450 4675);
FORCEADD OFFPAGE..4
(-750 3100);
FORCEPROP 2 LAST $XR1 53 
J 0
(-474 3100);
DISPLAY 0.638298 (-474 3100);
PAINT MONO (-474 3100);
FORCEPROP 2 LAST $XR0 52 
J 0
(-564 3100);
DISPLAY 0.638298 (-564 3100);
PAINT MONO (-564 3100);
FORCEPROP 2 LAST PATH I110
J 0
(-450 3150);
DISPLAY 0.680851 (-450 3150);
DISPLAY INVISIBLE (-450 3150);
FORCEPROP 2 LAST CDS_LIB standard
J 0
(-750 3100);
DISPLAY INVISIBLE (-750 3100);
FORCEPROP 1 LAST OFFPAGE TRUE
J 0
(-425 2975);
DISPLAY 0.872340 (-425 2975);
PAINT GREEN (-425 2975);
DISPLAY INVISIBLE (-425 2975);
FORCEPROP 1 LAST COMMENT_BODY TRUE
J 0
(-775 3000);
DISPLAY 0.872340 (-775 3000);
PAINT PEACH (-775 3000);
DISPLAY INVISIBLE (-775 3000);
FORCEADD OFFPAGE..2
(-750 3250);
FORCEPROP 2 LAST $XR0 15 
J 0
(-561 3250);
DISPLAY 0.638298 (-561 3250);
PAINT MONO (-561 3250);
FORCEPROP 2 LAST $XR1 49 
J 0
(-471 3250);
DISPLAY 0.638298 (-471 3250);
PAINT MONO (-471 3250);
FORCEPROP 2 LAST PATH I111
J 0
(-450 3300);
DISPLAY 0.680851 (-450 3300);
DISPLAY INVISIBLE (-450 3300);
FORCEPROP 2 LAST CDS_LIB standard
J 0
(-750 3250);
DISPLAY INVISIBLE (-750 3250);
FORCEPROP 1 LAST OFFPAGE TRUE
J 0
(-425 3125);
DISPLAY 0.872340 (-425 3125);
PAINT GREEN (-425 3125);
DISPLAY INVISIBLE (-425 3125);
FORCEPROP 1 LAST COMMENT_BODY TRUE
J 0
(-795 3155);
DISPLAY 0.872340 (-795 3155);
PAINT PEACH (-795 3155);
DISPLAY INVISIBLE (-795 3155);
FORCEADD OFFPAGE..4
(-750 3550);
FORCEPROP 2 LAST $XR0 13 
J 0
(-564 3550);
DISPLAY 0.638298 (-564 3550);
PAINT MONO (-564 3550);
FORCEPROP 2 LAST PATH I114
J 0
(-525 3600);
DISPLAY 0.680851 (-525 3600);
DISPLAY INVISIBLE (-525 3600);
FORCEPROP 2 LAST CDS_LIB standard
J 0
(-750 3550);
DISPLAY INVISIBLE (-750 3550);
FORCEPROP 1 LAST OFFPAGE TRUE
J 0
(-425 3425);
DISPLAY 0.872340 (-425 3425);
PAINT GREEN (-425 3425);
DISPLAY INVISIBLE (-425 3425);
FORCEPROP 1 LAST COMMENT_BODY TRUE
J 0
(-775 3450);
DISPLAY 0.872340 (-775 3450);
PAINT PEACH (-775 3450);
DISPLAY INVISIBLE (-775 3450);
FORCEADD OFFPAGE..4
(-750 3500);
FORCEPROP 2 LAST $XR0 13 
J 0
(-564 3500);
DISPLAY 0.638298 (-564 3500);
PAINT MONO (-564 3500);
FORCEPROP 2 LAST PATH I115
J 0
(-550 3550);
DISPLAY 0.680851 (-550 3550);
DISPLAY INVISIBLE (-550 3550);
FORCEPROP 2 LAST CDS_LIB standard
J 0
(-750 3500);
DISPLAY INVISIBLE (-750 3500);
FORCEPROP 1 LAST OFFPAGE TRUE
J 0
(-425 3375);
DISPLAY 0.872340 (-425 3375);
PAINT GREEN (-425 3375);
DISPLAY INVISIBLE (-425 3375);
FORCEPROP 1 LAST COMMENT_BODY TRUE
J 0
(-775 3400);
DISPLAY 0.872340 (-775 3400);
PAINT PEACH (-775 3400);
DISPLAY INVISIBLE (-775 3400);
FORCEADD OFFPAGE..4
(-750 3800);
FORCEPROP 2 LAST $XR0 10 
J 0
(-564 3800);
DISPLAY 0.638298 (-564 3800);
PAINT MONO (-564 3800);
FORCEPROP 2 LAST $XR1 11 
J 0
(-474 3800);
DISPLAY 0.638298 (-474 3800);
PAINT MONO (-474 3800);
FORCEPROP 2 LAST $XR2 13 
J 0
(-384 3800);
DISPLAY 0.638298 (-384 3800);
PAINT MONO (-384 3800);
FORCEPROP 2 LAST $XR3 28 
J 0
(-294 3800);
DISPLAY 0.638298 (-294 3800);
PAINT MONO (-294 3800);
FORCEPROP 2 LAST PATH I116
J 0
(-275 3850);
DISPLAY 0.680851 (-275 3850);
DISPLAY INVISIBLE (-275 3850);
FORCEPROP 2 LAST CDS_LIB standard
J 0
(-750 3800);
DISPLAY INVISIBLE (-750 3800);
FORCEPROP 1 LAST OFFPAGE TRUE
J 0
(-425 3675);
DISPLAY 0.872340 (-425 3675);
PAINT GREEN (-425 3675);
DISPLAY INVISIBLE (-425 3675);
FORCEPROP 1 LAST COMMENT_BODY TRUE
J 0
(-775 3700);
DISPLAY 0.872340 (-775 3700);
PAINT PEACH (-775 3700);
DISPLAY INVISIBLE (-775 3700);
FORCEADD OFFPAGE..4
(-750 3700);
FORCEPROP 2 LAST $XR0 28 
J 0
(-564 3700);
DISPLAY 0.638298 (-564 3700);
PAINT MONO (-564 3700);
FORCEPROP 2 LAST $XR1 15 
J 0
(-474 3700);
DISPLAY 0.638298 (-474 3700);
PAINT MONO (-474 3700);
FORCEPROP 2 LAST PATH I117
J 0
(-550 3750);
DISPLAY 0.680851 (-550 3750);
DISPLAY INVISIBLE (-550 3750);
FORCEPROP 2 LAST CDS_LIB standard
J 0
(-750 3700);
DISPLAY INVISIBLE (-750 3700);
FORCEPROP 1 LAST OFFPAGE TRUE
J 0
(-425 3575);
DISPLAY 0.872340 (-425 3575);
PAINT GREEN (-425 3575);
DISPLAY INVISIBLE (-425 3575);
FORCEPROP 1 LAST COMMENT_BODY TRUE
J 0
(-775 3600);
DISPLAY 0.872340 (-775 3600);
PAINT PEACH (-775 3600);
DISPLAY INVISIBLE (-775 3600);
FORCEADD OFFPAGE..3
(-750 3650);
FORCEPROP 2 LAST $XR0 27 
J 0
(-536 3650);
DISPLAY 0.638298 (-536 3650);
PAINT MONO (-536 3650);
FORCEPROP 2 LAST $XR1 15 
J 0
(-446 3650);
DISPLAY 0.638298 (-446 3650);
PAINT MONO (-446 3650);
FORCEPROP 2 LAST PATH I118
J 0
(-425 3700);
DISPLAY 0.680851 (-425 3700);
DISPLAY INVISIBLE (-425 3700);
FORCEPROP 2 LAST CDS_LIB standard
J 0
(-750 3650);
DISPLAY INVISIBLE (-750 3650);
FORCEPROP 1 LAST OFFPAGE TRUE
J 0
(-425 3525);
DISPLAY 0.872340 (-425 3525);
PAINT GREEN (-425 3525);
DISPLAY INVISIBLE (-425 3525);
FORCEPROP 1 LAST COMMENT_BODY TRUE
J 0
(-800 3550);
DISPLAY 0.872340 (-800 3550);
PAINT PEACH (-800 3550);
DISPLAY INVISIBLE (-800 3550);
FORCEADD OFFPAGE..2
(-750 3850);
FORCEPROP 2 LAST $XR0 15 
J 0
(-561 3850);
DISPLAY 0.638298 (-561 3850);
PAINT MONO (-561 3850);
FORCEPROP 2 LAST PATH I119
J 0
(-550 3900);
DISPLAY 0.680851 (-550 3900);
DISPLAY INVISIBLE (-550 3900);
FORCEPROP 2 LAST CDS_LIB standard
J 0
(-750 3850);
DISPLAY INVISIBLE (-750 3850);
FORCEPROP 1 LAST OFFPAGE TRUE
J 0
(-425 3725);
DISPLAY 0.872340 (-425 3725);
PAINT GREEN (-425 3725);
DISPLAY INVISIBLE (-425 3725);
FORCEPROP 1 LAST COMMENT_BODY TRUE
J 0
(-795 3755);
DISPLAY 0.872340 (-795 3755);
PAINT PEACH (-795 3755);
DISPLAY INVISIBLE (-795 3755);
FORCEADD OFFPAGE..2
(-775 5100);
FORCEPROP 2 LAST $XR0 15 
J 0
(-586 5100);
DISPLAY 0.638298 (-586 5100);
PAINT MONO (-586 5100);
FORCEPROP 1 LAST COMMENT_BODY TRUE
J 0
(-820 5005);
DISPLAY 0.872340 (-820 5005);
PAINT PEACH (-820 5005);
DISPLAY INVISIBLE (-820 5005);
FORCEPROP 1 LAST OFFPAGE TRUE
J 0
(-450 4975);
DISPLAY 0.872340 (-450 4975);
PAINT GREEN (-450 4975);
DISPLAY INVISIBLE (-450 4975);
FORCEPROP 2 LAST CDS_LIB standard
J 0
(-775 5100);
DISPLAY INVISIBLE (-775 5100);
FORCEPROP 2 LAST PATH I12
J 0
(-575 5150);
DISPLAY 0.680851 (-575 5150);
DISPLAY INVISIBLE (-575 5150);
FORCEADD OFFPAGE..2
(-750 4000);
FORCEPROP 2 LAST $XR0 22 
J 0
(-561 4000);
DISPLAY 0.638298 (-561 4000);
PAINT MONO (-561 4000);
FORCEPROP 2 LAST PATH I121
J 0
(-550 4050);
DISPLAY 0.680851 (-550 4050);
DISPLAY INVISIBLE (-550 4050);
FORCEPROP 2 LAST CDS_LIB standard
J 0
(-750 4000);
DISPLAY INVISIBLE (-750 4000);
FORCEPROP 1 LAST OFFPAGE TRUE
J 0
(-425 3875);
DISPLAY 0.872340 (-425 3875);
PAINT GREEN (-425 3875);
DISPLAY INVISIBLE (-425 3875);
FORCEPROP 1 LAST COMMENT_BODY TRUE
J 0
(-795 3905);
DISPLAY 0.872340 (-795 3905);
PAINT PEACH (-795 3905);
DISPLAY INVISIBLE (-795 3905);
FORCEADD UNIVERSAL_POWER..1
(-6000 2750);
FORCEPROP 3 LASTPIN (-6000 2700) SIG_NAME VCCIO1\g
J 0
(-5990 2710);
DISPLAY 0.659574 (-5990 2710);
PAINT MONO (-5990 2710);
DISPLAY INVISIBLE (-5990 2710);
FORCEPROP 1 LAST HDL_POWER VCCIO1
J 1
(-6000 2800);
DISPLAY 0.702128 (-6000 2800);
PAINT GREEN (-6000 2800);
FORCEPROP 2 LAST CDS_LIB logical_power
J 0
(-6000 2750);
DISPLAY INVISIBLE (-6000 2750);
FORCEPROP 1 LAST PATH I122
J 0
(-5950 2775);
DISPLAY 0.872340 (-5950 2775);
PAINT AQUA (-5950 2775);
DISPLAY INVISIBLE (-5950 2775);
FORCEADD UNIVERSAL_POWER..1
(-3500 2750);
FORCEPROP 3 LASTPIN (-3500 2700) SIG_NAME VCCIO1\g
J 0
(-3490 2710);
DISPLAY 0.659574 (-3490 2710);
PAINT MONO (-3490 2710);
DISPLAY INVISIBLE (-3490 2710);
FORCEPROP 1 LAST HDL_POWER VCCIO1
J 1
(-3500 2800);
DISPLAY 0.702128 (-3500 2800);
PAINT GREEN (-3500 2800);
FORCEPROP 2 LAST CDS_LIB logical_power
J 0
(-3500 2750);
DISPLAY INVISIBLE (-3500 2750);
FORCEPROP 1 LAST PATH I123
J 0
(-3450 2775);
DISPLAY 0.872340 (-3450 2775);
PAINT AQUA (-3450 2775);
DISPLAY INVISIBLE (-3450 2775);
FORCEADD OFFPAGE..1
(-8550 5050);
FORCEPROP 2 LAST $XR0 13 
J 0
(-8801 5050);
DISPLAY 0.638298 (-8801 5050);
PAINT MONO (-8801 5050);
FORCEPROP 2 LAST CDS_LIB standard
J 0
(-8550 5050);
DISPLAY INVISIBLE (-8550 5050);
FORCEPROP 2 LAST PATH I124
J 0
(-8500 5125);
DISPLAY 0.680851 (-8500 5125);
DISPLAY INVISIBLE (-8500 5125);
FORCEPROP 1 LAST COMMENT_BODY TRUE
J 0
(-8425 4950);
DISPLAY 0.872340 (-8425 4950);
PAINT GREEN (-8425 4950);
DISPLAY INVISIBLE (-8425 4950);
FORCEPROP 1 LAST OFFPAGE TRUE
J 0
(-8225 4925);
DISPLAY 0.872340 (-8225 4925);
DISPLAY INVISIBLE (-8225 4925);
FORCEADD OFFPAGE..5
(-8550 5100);
FORCEPROP 2 LAST $XR0 27 
J 0
(-8774 5100);
DISPLAY 0.638298 (-8774 5100);
PAINT MONO (-8774 5100);
FORCEPROP 2 LAST $XR1 13 
J 0
(-8864 5100);
DISPLAY 0.638298 (-8864 5100);
PAINT MONO (-8864 5100);
FORCEPROP 2 LAST CDS_LIB standard
J 0
(-8550 5100);
DISPLAY INVISIBLE (-8550 5100);
FORCEPROP 2 LAST PATH I125
J 0
(-8500 5175);
DISPLAY 0.680851 (-8500 5175);
DISPLAY INVISIBLE (-8500 5175);
FORCEPROP 1 LAST COMMENT_BODY TRUE
J 0
(-8450 5025);
DISPLAY 0.872340 (-8450 5025);
PAINT PEACH (-8450 5025);
DISPLAY INVISIBLE (-8450 5025);
FORCEPROP 1 LAST OFFPAGE TRUE
J 0
(-8225 4975);
DISPLAY 0.872340 (-8225 4975);
PAINT GREEN (-8225 4975);
DISPLAY INVISIBLE (-8225 4975);
FORCEADD OFFPAGE..4
(-775 5050);
FORCEPROP 2 LAST $XR0 15 
J 0
(-589 5050);
DISPLAY 0.638298 (-589 5050);
PAINT MONO (-589 5050);
FORCEPROP 1 LAST COMMENT_BODY TRUE
J 0
(-800 4950);
DISPLAY 0.872340 (-800 4950);
PAINT PEACH (-800 4950);
DISPLAY INVISIBLE (-800 4950);
FORCEPROP 1 LAST OFFPAGE TRUE
J 0
(-450 4925);
DISPLAY 0.872340 (-450 4925);
PAINT GREEN (-450 4925);
DISPLAY INVISIBLE (-450 4925);
FORCEPROP 2 LAST CDS_LIB standard
J 0
(-775 5050);
DISPLAY INVISIBLE (-775 5050);
FORCEPROP 2 LAST PATH I13
J 0
(-575 5100);
DISPLAY 0.680851 (-575 5100);
DISPLAY INVISIBLE (-575 5100);
FORCEADD Q_RES..1
(-6800 3600);
FORCEPROP 1 LAST MATERIAL EMPTY
J 2
(-6475 3600);
DISPLAY 0.510638 (-6475 3600);
PAINT SKYBLUE (-6475 3600);
FORCEPROP 1 LAST VALUE 0
J 2
(-6650 3600);
DISPLAY 0.510638 (-6650 3600);
PAINT SKYBLUE (-6650 3600);
FORCEPROP 1 LAST PATH I131
J 0
(-6850 3750);
DISPLAY 0.978723 (-6850 3750);
PAINT WHITE (-6850 3750);
DISPLAY INVISIBLE (-6850 3750);
FORCEPROP 2 LAST SEC_TYPE 0402LF
J 0
(-6850 3800);
DISPLAY 0.680851 (-6850 3800);
DISPLAY INVISIBLE (-6850 3800);
FORCEPROP 2 LAST CDS_LIB pure_quanta
J 0
(-6800 3600);
DISPLAY INVISIBLE (-6800 3600);
FORCEPROP 1 LAST TOLERANCE 5%
J 0
(-6875 3700);
DISPLAY 0.510638 (-6875 3700);
PAINT SKYBLUE (-6875 3700);
DISPLAY INVISIBLE (-6875 3700);
FORCEPROP 1 LAST WATTAGE 1/16W
J 2
(-6450 3700);
DISPLAY 0.510638 (-6450 3700);
PAINT SKYBLUE (-6450 3700);
DISPLAY INVISIBLE (-6450 3700);
FORCEPROP 1 LAST PACK_TYPE 0402LF
J 0
(-6825 3650);
DISPLAY 0.510638 (-6825 3650);
PAINT SKYBLUE (-6825 3650);
DISPLAY INVISIBLE (-6825 3650);
FORCEPROP 1 LAST PART_NUMBER CS00002JB13
J 0
(-6900 3675);
DISPLAY 0.510638 (-6900 3675);
PAINT WHITE (-6900 3675);
DISPLAY INVISIBLE (-6900 3675);
FORCEPROP 1 LAST $LOCATION R463
J 0
(-7075 3600);
DISPLAY 0.702128 (-7075 3600);
PAINT YELLOW (-7075 3600);
FORCEPROP 1 LASTPIN (-6900 3600) $PN 1
J 0
(-6888 3612);
DISPLAY 0.808511 (-6888 3612);
PAINT WHITE (-6888 3612);
FORCEPROP 1 LASTPIN (-6700 3600) $PN 2
J 0
(-6738 3612);
DISPLAY 0.808511 (-6738 3612);
PAINT WHITE (-6738 3612);
FORCEPROP 0 LAST CDS_LOCATION R463
J 0
(-7075 3650);
DISPLAY 0.680851 (-7075 3650);
DISPLAY INVISIBLE (-7075 3650);
FORCEPROP 2 LAST SEC 1
J 0
(-6850 3800);
DISPLAY 0.680851 (-6850 3800);
PAINT MONO (-6850 3800);
DISPLAY INVISIBLE (-6850 3800);
FORCEADD OFFPAGE..1
(-8050 3600);
FORCEPROP 2 LAST $XR0 13 
J 0
(-8271 3600);
DISPLAY 0.638298 (-8271 3600);
PAINT MONO (-8271 3600);
FORCEPROP 2 LAST $XR1 22 
J 0
(-8361 3600);
DISPLAY 0.638298 (-8361 3600);
PAINT MONO (-8361 3600);
FORCEPROP 2 LAST PATH I132
J 0
(-8250 3650);
DISPLAY 0.680851 (-8250 3650);
DISPLAY INVISIBLE (-8250 3650);
FORCEPROP 2 LAST CDS_LIB standard
J 0
(-8050 3600);
DISPLAY INVISIBLE (-8050 3600);
FORCEPROP 1 LAST OFFPAGE TRUE
J 0
(-7725 3475);
DISPLAY 0.872340 (-7725 3475);
DISPLAY INVISIBLE (-7725 3475);
FORCEPROP 1 LAST COMMENT_BODY TRUE
J 0
(-7925 3500);
DISPLAY 0.872340 (-7925 3500);
PAINT GREEN (-7925 3500);
DISPLAY INVISIBLE (-7925 3500);
FORCEADD VCCAUX15..1
(-8525 2425);
FORCEPROP 3 LASTPIN (-8525 2375) SIG_NAME P3V3_AUX\g
J 0
(-8515 2385);
DISPLAY 0.659574 (-8515 2385);
PAINT MONO (-8515 2385);
DISPLAY INVISIBLE (-8515 2385);
FORCEPROP 1 LAST HDL_POWER P3V3_AUX
J 1
(-8525 2475);
DISPLAY 0.702128 (-8525 2475);
PAINT GREEN (-8525 2475);
FORCEPROP 2 LAST CDS_LIB logical_power
J 0
(-8525 2425);
DISPLAY INVISIBLE (-8525 2425);
FORCEPROP 1 LAST PATH I133
J 0
(-8475 2450);
DISPLAY 0.872340 (-8475 2450);
PAINT AQUA (-8475 2450);
DISPLAY INVISIBLE (-8475 2450);
FORCEADD OFFPAGE..2
(-6700 2075);
FORCEPROP 2 LAST CDS_LIB standard
J 0
(-6700 2075);
DISPLAY INVISIBLE (-6700 2075);
FORCEPROP 2 LAST PATH I134
J 0
(-6525 2150);
DISPLAY 0.680851 (-6525 2150);
DISPLAY INVISIBLE (-6525 2150);
FORCEPROP 1 LAST OFFPAGE TRUE
J 0
(-6375 1950);
DISPLAY 0.872340 (-6375 1950);
PAINT GREEN (-6375 1950);
DISPLAY INVISIBLE (-6375 1950);
FORCEPROP 1 LAST COMMENT_BODY TRUE
J 0
(-6745 1980);
DISPLAY 0.872340 (-6745 1980);
PAINT PEACH (-6745 1980);
DISPLAY INVISIBLE (-6745 1980);
FORCEADD Q_RES..1
(-7950 2075);
FORCEPROP 1 LAST VALUE 4.7K
J 0
(-7775 2075);
DISPLAY 0.510638 (-7775 2075);
PAINT SKYBLUE (-7775 2075);
FORCEPROP 1 LAST MATERIAL EMPTY
J 0
(-7600 2075);
DISPLAY 0.510638 (-7600 2075);
PAINT RED (-7600 2075);
FORCEPROP 2 LAST CDS_LIB pure_quanta
J 0
(-7950 2075);
DISPLAY INVISIBLE (-7950 2075);
FORCEPROP 1 LAST PATH I136
J 0
(-8000 2225);
DISPLAY 0.978723 (-8000 2225);
PAINT WHITE (-8000 2225);
DISPLAY INVISIBLE (-8000 2225);
FORCEPROP 1 LAST PART_NUMBER CS24702FB06
J 0
(-8000 2175);
DISPLAY 0.510638 (-8000 2175);
PAINT WHITE (-8000 2175);
DISPLAY INVISIBLE (-8000 2175);
FORCEPROP 1 LAST PACK_TYPE 0402LF
J 0
(-7700 1925);
DISPLAY 0.510638 (-7700 1925);
PAINT SKYBLUE (-7700 1925);
DISPLAY INVISIBLE (-7700 1925);
FORCEPROP 1 LAST WATTAGE 1/16W
J 2
(-7975 1925);
DISPLAY 0.510638 (-7975 1925);
PAINT SKYBLUE (-7975 1925);
DISPLAY INVISIBLE (-7975 1925);
FORCEPROP 1 LAST TOLERANCE 1%
J 0
(-7950 1975);
DISPLAY 0.510638 (-7950 1975);
PAINT SKYBLUE (-7950 1975);
DISPLAY INVISIBLE (-7950 1975);
FORCEPROP 1 LAST $LOCATION R472
J 0
(-8275 2075);
DISPLAY 0.702128 (-8275 2075);
PAINT YELLOW (-8275 2075);
FORCEPROP 1 LASTPIN (-8050 2075) $PN 1
J 0
(-8038 2087);
DISPLAY 0.787234 (-8038 2087);
PAINT MONO (-8038 2087);
FORCEPROP 1 LASTPIN (-7850 2075) $PN 2
J 0
(-7888 2087);
DISPLAY 0.787234 (-7888 2087);
PAINT MONO (-7888 2087);
FORCEPROP 0 LAST CDS_LOCATION R472
J 0
(-8275 2125);
DISPLAY 0.680851 (-8275 2125);
DISPLAY INVISIBLE (-8275 2125);
FORCEPROP 0 LAST $SEC 1
J 0
(-8275 2125);
DISPLAY 0.680851 (-8275 2125);
PAINT MONO (-8275 2125);
DISPLAY INVISIBLE (-8275 2125);
FORCEPROP 0 LAST CDS_SEC 1
J 0
(-8275 2125);
DISPLAY 0.680851 (-8275 2125);
DISPLAY INVISIBLE (-8275 2125);
FORCEADD Q_RES..1
(-7300 4500);
FORCEPROP 1 LAST VALUE 33.2
J 2
(-7075 4500);
DISPLAY 0.510638 (-7075 4500);
PAINT SKYBLUE (-7075 4500);
FORCEPROP 1 LAST MATERIAL CHIP
J 0
(-7050 4500);
DISPLAY 0.510638 (-7050 4500);
PAINT SKYBLUE (-7050 4500);
FORCEPROP 2 LAST CDS_LIB pure_quanta
J 0
(-7300 4500);
DISPLAY INVISIBLE (-7300 4500);
FORCEPROP 1 LAST PATH I137
J 0
(-7350 4650);
DISPLAY 0.978723 (-7350 4650);
PAINT WHITE (-7350 4650);
DISPLAY INVISIBLE (-7350 4650);
FORCEPROP 1 LAST PACK_TYPE 0402LF
J 0
(-7300 4400);
DISPLAY 0.510638 (-7300 4400);
PAINT SKYBLUE (-7300 4400);
DISPLAY INVISIBLE (-7300 4400);
FORCEPROP 1 LAST WATTAGE 1/16W
J 2
(-7175 4425);
DISPLAY 0.510638 (-7175 4425);
PAINT SKYBLUE (-7175 4425);
DISPLAY INVISIBLE (-7175 4425);
FORCEPROP 1 LAST PART_NUMBER CS03322FB03
J 0
(-7375 4375);
DISPLAY 0.510638 (-7375 4375);
PAINT WHITE (-7375 4375);
DISPLAY INVISIBLE (-7375 4375);
FORCEPROP 1 LAST TOLERANCE 1%
J 0
(-7275 4450);
DISPLAY 0.510638 (-7275 4450);
PAINT SKYBLUE (-7275 4450);
DISPLAY INVISIBLE (-7275 4450);
FORCEPROP 1 LAST LOCATION R773
J 0
(-7525 4500);
DISPLAY 0.702128 (-7525 4500);
PAINT YELLOW (-7525 4500);
FORCEPROP 1 LASTPIN (-7400 4500) $PN 1
J 0
(-7388 4512);
DISPLAY 0.787234 (-7388 4512);
PAINT MONO (-7388 4512);
FORCEPROP 1 LASTPIN (-7200 4500) $PN 2
J 0
(-7238 4512);
DISPLAY 0.787234 (-7238 4512);
PAINT MONO (-7238 4512);
FORCEPROP 0 LAST $SEC 1
J 0
(-7525 4550);
DISPLAY 0.680851 (-7525 4550);
PAINT MONO (-7525 4550);
DISPLAY INVISIBLE (-7525 4550);
FORCEPROP 0 LAST CDS_SEC 1
J 0
(-7525 4550);
DISPLAY 0.680851 (-7525 4550);
DISPLAY INVISIBLE (-7525 4550);
FORCEADD Q_RES..1
(-7300 4450);
FORCEPROP 1 LAST MATERIAL CHIP
J 0
(-7050 4450);
DISPLAY 0.510638 (-7050 4450);
PAINT SKYBLUE (-7050 4450);
FORCEPROP 1 LAST VALUE 33.2
J 2
(-7075 4450);
DISPLAY 0.510638 (-7075 4450);
PAINT SKYBLUE (-7075 4450);
FORCEPROP 2 LAST CDS_LIB pure_quanta
J 0
(-7300 4450);
DISPLAY INVISIBLE (-7300 4450);
FORCEPROP 1 LAST PATH I138
J 0
(-7350 4600);
DISPLAY 0.978723 (-7350 4600);
PAINT WHITE (-7350 4600);
DISPLAY INVISIBLE (-7350 4600);
FORCEPROP 1 LAST PACK_TYPE 0402LF
J 0
(-7300 4350);
DISPLAY 0.510638 (-7300 4350);
PAINT SKYBLUE (-7300 4350);
DISPLAY INVISIBLE (-7300 4350);
FORCEPROP 1 LAST WATTAGE 1/16W
J 2
(-7175 4375);
DISPLAY 0.510638 (-7175 4375);
PAINT SKYBLUE (-7175 4375);
DISPLAY INVISIBLE (-7175 4375);
FORCEPROP 1 LAST PART_NUMBER CS03322FB03
J 0
(-7375 4325);
DISPLAY 0.510638 (-7375 4325);
PAINT WHITE (-7375 4325);
DISPLAY INVISIBLE (-7375 4325);
FORCEPROP 1 LAST TOLERANCE 1%
J 0
(-7275 4400);
DISPLAY 0.510638 (-7275 4400);
PAINT SKYBLUE (-7275 4400);
DISPLAY INVISIBLE (-7275 4400);
FORCEPROP 1 LAST LOCATION R825
J 0
(-7525 4450);
DISPLAY 0.702128 (-7525 4450);
PAINT YELLOW (-7525 4450);
FORCEPROP 1 LASTPIN (-7400 4450) $PN 1
J 0
(-7388 4462);
DISPLAY 0.787234 (-7388 4462);
PAINT MONO (-7388 4462);
FORCEPROP 1 LASTPIN (-7200 4450) $PN 2
J 0
(-7238 4462);
DISPLAY 0.787234 (-7238 4462);
PAINT MONO (-7238 4462);
FORCEPROP 0 LAST $SEC 1
J 0
(-7525 4500);
DISPLAY 0.680851 (-7525 4500);
PAINT MONO (-7525 4500);
DISPLAY INVISIBLE (-7525 4500);
FORCEPROP 0 LAST CDS_SEC 1
J 0
(-7525 4500);
DISPLAY 0.680851 (-7525 4500);
DISPLAY INVISIBLE (-7525 4500);
FORCEADD Q_RES..1
(-7300 4350);
FORCEPROP 1 LAST VALUE 33.2
J 2
(-7075 4350);
DISPLAY 0.510638 (-7075 4350);
PAINT SKYBLUE (-7075 4350);
FORCEPROP 1 LAST MATERIAL CHIP
J 0
(-7050 4350);
DISPLAY 0.510638 (-7050 4350);
PAINT SKYBLUE (-7050 4350);
FORCEPROP 2 LAST CDS_LIB pure_quanta
J 0
(-7300 4350);
DISPLAY INVISIBLE (-7300 4350);
FORCEPROP 1 LAST PATH I139
J 0
(-7350 4500);
DISPLAY 0.978723 (-7350 4500);
PAINT WHITE (-7350 4500);
DISPLAY INVISIBLE (-7350 4500);
FORCEPROP 1 LAST PACK_TYPE 0402LF
J 0
(-7300 4250);
DISPLAY 0.510638 (-7300 4250);
PAINT SKYBLUE (-7300 4250);
DISPLAY INVISIBLE (-7300 4250);
FORCEPROP 1 LAST WATTAGE 1/16W
J 2
(-7175 4275);
DISPLAY 0.510638 (-7175 4275);
PAINT SKYBLUE (-7175 4275);
DISPLAY INVISIBLE (-7175 4275);
FORCEPROP 1 LAST PART_NUMBER CS03322FB03
J 0
(-7375 4225);
DISPLAY 0.510638 (-7375 4225);
PAINT WHITE (-7375 4225);
DISPLAY INVISIBLE (-7375 4225);
FORCEPROP 1 LAST TOLERANCE 1%
J 0
(-7275 4300);
DISPLAY 0.510638 (-7275 4300);
PAINT SKYBLUE (-7275 4300);
DISPLAY INVISIBLE (-7275 4300);
FORCEPROP 1 LAST LOCATION R833
J 0
(-7525 4350);
DISPLAY 0.702128 (-7525 4350);
PAINT YELLOW (-7525 4350);
FORCEPROP 1 LASTPIN (-7400 4350) $PN 1
J 0
(-7388 4362);
DISPLAY 0.787234 (-7388 4362);
PAINT MONO (-7388 4362);
FORCEPROP 1 LASTPIN (-7200 4350) $PN 2
J 0
(-7238 4362);
DISPLAY 0.787234 (-7238 4362);
PAINT MONO (-7238 4362);
FORCEPROP 0 LAST $SEC 1
J 0
(-7525 4400);
DISPLAY 0.680851 (-7525 4400);
PAINT MONO (-7525 4400);
DISPLAY INVISIBLE (-7525 4400);
FORCEPROP 0 LAST CDS_SEC 1
J 0
(-7525 4400);
DISPLAY 0.680851 (-7525 4400);
DISPLAY INVISIBLE (-7525 4400);
FORCEADD OFFPAGE..2
(-775 4950);
FORCEPROP 2 LAST $XR0 15 
J 0
(-586 4950);
DISPLAY 0.638298 (-586 4950);
PAINT MONO (-586 4950);
FORCEPROP 1 LAST COMMENT_BODY TRUE
J 0
(-820 4855);
DISPLAY 0.872340 (-820 4855);
PAINT PEACH (-820 4855);
DISPLAY INVISIBLE (-820 4855);
FORCEPROP 1 LAST OFFPAGE TRUE
J 0
(-450 4825);
DISPLAY 0.872340 (-450 4825);
PAINT GREEN (-450 4825);
DISPLAY INVISIBLE (-450 4825);
FORCEPROP 2 LAST CDS_LIB standard
J 0
(-775 4950);
DISPLAY INVISIBLE (-775 4950);
FORCEPROP 2 LAST PATH I14
J 0
(-575 5000);
DISPLAY 0.680851 (-575 5000);
DISPLAY INVISIBLE (-575 5000);
FORCEADD Q_RES..1
(-7300 4300);
FORCEPROP 1 LAST MATERIAL CHIP
J 0
(-7050 4300);
DISPLAY 0.510638 (-7050 4300);
PAINT SKYBLUE (-7050 4300);
FORCEPROP 1 LAST VALUE 33.2
J 2
(-7075 4300);
DISPLAY 0.510638 (-7075 4300);
PAINT SKYBLUE (-7075 4300);
FORCEPROP 2 LAST CDS_LIB pure_quanta
J 0
(-7300 4300);
DISPLAY INVISIBLE (-7300 4300);
FORCEPROP 1 LAST PATH I140
J 0
(-7350 4450);
DISPLAY 0.978723 (-7350 4450);
PAINT WHITE (-7350 4450);
DISPLAY INVISIBLE (-7350 4450);
FORCEPROP 1 LAST PACK_TYPE 0402LF
J 0
(-7300 4200);
DISPLAY 0.510638 (-7300 4200);
PAINT SKYBLUE (-7300 4200);
DISPLAY INVISIBLE (-7300 4200);
FORCEPROP 1 LAST WATTAGE 1/16W
J 2
(-7175 4225);
DISPLAY 0.510638 (-7175 4225);
PAINT SKYBLUE (-7175 4225);
DISPLAY INVISIBLE (-7175 4225);
FORCEPROP 1 LAST PART_NUMBER CS03322FB03
J 0
(-7375 4175);
DISPLAY 0.510638 (-7375 4175);
PAINT WHITE (-7375 4175);
DISPLAY INVISIBLE (-7375 4175);
FORCEPROP 1 LAST TOLERANCE 1%
J 0
(-7275 4250);
DISPLAY 0.510638 (-7275 4250);
PAINT SKYBLUE (-7275 4250);
DISPLAY INVISIBLE (-7275 4250);
FORCEPROP 1 LAST LOCATION R769
J 0
(-7525 4300);
DISPLAY 0.702128 (-7525 4300);
PAINT YELLOW (-7525 4300);
FORCEPROP 1 LASTPIN (-7400 4300) $PN 1
J 0
(-7388 4312);
DISPLAY 0.787234 (-7388 4312);
PAINT MONO (-7388 4312);
FORCEPROP 1 LASTPIN (-7200 4300) $PN 2
J 0
(-7238 4312);
DISPLAY 0.787234 (-7238 4312);
PAINT MONO (-7238 4312);
FORCEPROP 0 LAST $SEC 1
J 0
(-7525 4350);
DISPLAY 0.680851 (-7525 4350);
PAINT MONO (-7525 4350);
DISPLAY INVISIBLE (-7525 4350);
FORCEPROP 0 LAST CDS_SEC 1
J 0
(-7525 4350);
DISPLAY 0.680851 (-7525 4350);
DISPLAY INVISIBLE (-7525 4350);
FORCEADD Q_RES..1
(-7300 4050);
FORCEPROP 1 LAST VALUE 33.2
J 2
(-7075 4050);
DISPLAY 0.510638 (-7075 4050);
PAINT SKYBLUE (-7075 4050);
FORCEPROP 1 LAST MATERIAL CHIP
J 0
(-7050 4050);
DISPLAY 0.510638 (-7050 4050);
PAINT SKYBLUE (-7050 4050);
FORCEPROP 2 LAST CDS_LIB pure_quanta
J 0
(-7300 4050);
DISPLAY INVISIBLE (-7300 4050);
FORCEPROP 1 LAST PATH I141
J 0
(-7350 4200);
DISPLAY 0.978723 (-7350 4200);
PAINT WHITE (-7350 4200);
DISPLAY INVISIBLE (-7350 4200);
FORCEPROP 1 LAST PACK_TYPE 0402LF
J 0
(-7300 3950);
DISPLAY 0.510638 (-7300 3950);
PAINT SKYBLUE (-7300 3950);
DISPLAY INVISIBLE (-7300 3950);
FORCEPROP 1 LAST WATTAGE 1/16W
J 2
(-7175 3975);
DISPLAY 0.510638 (-7175 3975);
PAINT SKYBLUE (-7175 3975);
DISPLAY INVISIBLE (-7175 3975);
FORCEPROP 1 LAST PART_NUMBER CS03322FB03
J 0
(-7375 3925);
DISPLAY 0.510638 (-7375 3925);
PAINT WHITE (-7375 3925);
DISPLAY INVISIBLE (-7375 3925);
FORCEPROP 1 LAST TOLERANCE 1%
J 0
(-7275 4000);
DISPLAY 0.510638 (-7275 4000);
PAINT SKYBLUE (-7275 4000);
DISPLAY INVISIBLE (-7275 4000);
FORCEPROP 1 LAST LOCATION R263
J 0
(-7525 4050);
DISPLAY 0.702128 (-7525 4050);
PAINT YELLOW (-7525 4050);
FORCEPROP 1 LASTPIN (-7400 4050) $PN 1
J 0
(-7388 4062);
DISPLAY 0.787234 (-7388 4062);
PAINT MONO (-7388 4062);
FORCEPROP 1 LASTPIN (-7200 4050) $PN 2
J 0
(-7238 4062);
DISPLAY 0.787234 (-7238 4062);
PAINT MONO (-7238 4062);
FORCEPROP 0 LAST $SEC 1
J 0
(-7525 4100);
DISPLAY 0.680851 (-7525 4100);
PAINT MONO (-7525 4100);
DISPLAY INVISIBLE (-7525 4100);
FORCEPROP 0 LAST CDS_SEC 1
J 0
(-7525 4100);
DISPLAY 0.680851 (-7525 4100);
DISPLAY INVISIBLE (-7525 4100);
FORCEADD Q_RES..1
(-1800 3800);
FORCEPROP 1 LAST VALUE 33.2
J 2
(-1575 3800);
DISPLAY 0.510638 (-1575 3800);
PAINT SKYBLUE (-1575 3800);
FORCEPROP 1 LAST MATERIAL CHIP
J 0
(-1550 3800);
DISPLAY 0.510638 (-1550 3800);
PAINT SKYBLUE (-1550 3800);
FORCEPROP 2 LAST CDS_LIB pure_quanta
J 0
(-1800 3800);
DISPLAY INVISIBLE (-1800 3800);
FORCEPROP 1 LAST PATH I142
J 0
(-1850 3950);
DISPLAY 0.978723 (-1850 3950);
PAINT WHITE (-1850 3950);
DISPLAY INVISIBLE (-1850 3950);
FORCEPROP 1 LAST PACK_TYPE 0402LF
J 0
(-1800 3700);
DISPLAY 0.510638 (-1800 3700);
PAINT SKYBLUE (-1800 3700);
DISPLAY INVISIBLE (-1800 3700);
FORCEPROP 1 LAST WATTAGE 1/16W
J 2
(-1675 3725);
DISPLAY 0.510638 (-1675 3725);
PAINT SKYBLUE (-1675 3725);
DISPLAY INVISIBLE (-1675 3725);
FORCEPROP 1 LAST PART_NUMBER CS03322FB03
J 0
(-1875 3675);
DISPLAY 0.510638 (-1875 3675);
PAINT WHITE (-1875 3675);
DISPLAY INVISIBLE (-1875 3675);
FORCEPROP 1 LAST TOLERANCE 1%
J 0
(-1775 3750);
DISPLAY 0.510638 (-1775 3750);
PAINT SKYBLUE (-1775 3750);
DISPLAY INVISIBLE (-1775 3750);
FORCEPROP 1 LAST LOCATION R841
J 0
(-2025 3800);
DISPLAY 0.702128 (-2025 3800);
PAINT YELLOW (-2025 3800);
FORCEPROP 1 LASTPIN (-1900 3800) $PN 1
J 0
(-1888 3812);
DISPLAY 0.787234 (-1888 3812);
PAINT MONO (-1888 3812);
FORCEPROP 1 LASTPIN (-1700 3800) $PN 2
J 0
(-1738 3812);
DISPLAY 0.787234 (-1738 3812);
PAINT MONO (-1738 3812);
FORCEPROP 0 LAST $SEC 1
J 0
(-2025 3850);
DISPLAY 0.680851 (-2025 3850);
PAINT MONO (-2025 3850);
DISPLAY INVISIBLE (-2025 3850);
FORCEPROP 0 LAST CDS_SEC 1
J 0
(-2025 3850);
DISPLAY 0.680851 (-2025 3850);
DISPLAY INVISIBLE (-2025 3850);
FORCEADD Q_RES..1
(-1800 4000);
FORCEPROP 1 LAST MATERIAL CHIP
J 0
(-1550 4000);
DISPLAY 0.510638 (-1550 4000);
PAINT SKYBLUE (-1550 4000);
FORCEPROP 1 LAST VALUE 33.2
J 2
(-1575 4000);
DISPLAY 0.510638 (-1575 4000);
PAINT SKYBLUE (-1575 4000);
FORCEPROP 2 LAST CDS_LIB pure_quanta
J 0
(-1800 4000);
DISPLAY INVISIBLE (-1800 4000);
FORCEPROP 1 LAST PATH I143
J 0
(-1850 4150);
DISPLAY 0.978723 (-1850 4150);
PAINT WHITE (-1850 4150);
DISPLAY INVISIBLE (-1850 4150);
FORCEPROP 1 LAST PACK_TYPE 0402LF
J 0
(-1800 3900);
DISPLAY 0.510638 (-1800 3900);
PAINT SKYBLUE (-1800 3900);
DISPLAY INVISIBLE (-1800 3900);
FORCEPROP 1 LAST WATTAGE 1/16W
J 2
(-1675 3925);
DISPLAY 0.510638 (-1675 3925);
PAINT SKYBLUE (-1675 3925);
DISPLAY INVISIBLE (-1675 3925);
FORCEPROP 1 LAST PART_NUMBER CS03322FB03
J 0
(-1875 3875);
DISPLAY 0.510638 (-1875 3875);
PAINT WHITE (-1875 3875);
DISPLAY INVISIBLE (-1875 3875);
FORCEPROP 1 LAST TOLERANCE 1%
J 0
(-1775 3950);
DISPLAY 0.510638 (-1775 3950);
PAINT SKYBLUE (-1775 3950);
DISPLAY INVISIBLE (-1775 3950);
FORCEPROP 1 LAST LOCATION R638
J 0
(-2025 4000);
DISPLAY 0.702128 (-2025 4000);
PAINT YELLOW (-2025 4000);
FORCEPROP 1 LASTPIN (-1900 4000) $PN 1
J 0
(-1888 4012);
DISPLAY 0.787234 (-1888 4012);
PAINT MONO (-1888 4012);
FORCEPROP 1 LASTPIN (-1700 4000) $PN 2
J 0
(-1738 4012);
DISPLAY 0.787234 (-1738 4012);
PAINT MONO (-1738 4012);
FORCEPROP 0 LAST $SEC 1
J 0
(-2025 4050);
DISPLAY 0.680851 (-2025 4050);
PAINT MONO (-2025 4050);
DISPLAY INVISIBLE (-2025 4050);
FORCEPROP 0 LAST CDS_SEC 1
J 0
(-2025 4050);
DISPLAY 0.680851 (-2025 4050);
DISPLAY INVISIBLE (-2025 4050);
FORCEADD Q_RES..1
(-2250 4350);
FORCEPROP 1 LAST VALUE 33.2
J 2
(-2025 4350);
DISPLAY 0.510638 (-2025 4350);
PAINT SKYBLUE (-2025 4350);
FORCEPROP 1 LAST MATERIAL CHIP
J 0
(-2000 4350);
DISPLAY 0.510638 (-2000 4350);
PAINT SKYBLUE (-2000 4350);
FORCEPROP 2 LAST CDS_LIB pure_quanta
J 0
(-2250 4350);
DISPLAY INVISIBLE (-2250 4350);
FORCEPROP 1 LAST PATH I144
J 0
(-2300 4500);
DISPLAY 0.978723 (-2300 4500);
PAINT WHITE (-2300 4500);
DISPLAY INVISIBLE (-2300 4500);
FORCEPROP 1 LAST PACK_TYPE 0402LF
J 0
(-2250 4250);
DISPLAY 0.510638 (-2250 4250);
PAINT SKYBLUE (-2250 4250);
DISPLAY INVISIBLE (-2250 4250);
FORCEPROP 1 LAST WATTAGE 1/16W
J 2
(-2125 4275);
DISPLAY 0.510638 (-2125 4275);
PAINT SKYBLUE (-2125 4275);
DISPLAY INVISIBLE (-2125 4275);
FORCEPROP 1 LAST PART_NUMBER CS03322FB03
J 0
(-2325 4225);
DISPLAY 0.510638 (-2325 4225);
PAINT WHITE (-2325 4225);
DISPLAY INVISIBLE (-2325 4225);
FORCEPROP 1 LAST TOLERANCE 1%
J 0
(-2225 4300);
DISPLAY 0.510638 (-2225 4300);
PAINT SKYBLUE (-2225 4300);
DISPLAY INVISIBLE (-2225 4300);
FORCEPROP 1 LAST LOCATION R536
J 0
(-2475 4350);
DISPLAY 0.702128 (-2475 4350);
PAINT YELLOW (-2475 4350);
FORCEPROP 1 LASTPIN (-2350 4350) $PN 1
J 0
(-2338 4362);
DISPLAY 0.787234 (-2338 4362);
PAINT MONO (-2338 4362);
FORCEPROP 1 LASTPIN (-2150 4350) $PN 2
J 0
(-2188 4362);
DISPLAY 0.787234 (-2188 4362);
PAINT MONO (-2188 4362);
FORCEPROP 0 LAST $SEC 1
J 0
(-2475 4400);
DISPLAY 0.680851 (-2475 4400);
PAINT MONO (-2475 4400);
DISPLAY INVISIBLE (-2475 4400);
FORCEPROP 0 LAST CDS_SEC 1
J 0
(-2475 4400);
DISPLAY 0.680851 (-2475 4400);
DISPLAY INVISIBLE (-2475 4400);
FORCEADD Q_RES..1
(-2250 4300);
FORCEPROP 1 LAST VALUE 33.2
J 2
(-2025 4300);
DISPLAY 0.510638 (-2025 4300);
PAINT SKYBLUE (-2025 4300);
FORCEPROP 1 LAST MATERIAL CHIP
J 0
(-2000 4300);
DISPLAY 0.510638 (-2000 4300);
PAINT SKYBLUE (-2000 4300);
FORCEPROP 2 LAST CDS_LIB pure_quanta
J 0
(-2250 4300);
DISPLAY INVISIBLE (-2250 4300);
FORCEPROP 1 LAST PATH I145
J 0
(-2300 4450);
DISPLAY 0.978723 (-2300 4450);
PAINT WHITE (-2300 4450);
DISPLAY INVISIBLE (-2300 4450);
FORCEPROP 1 LAST PACK_TYPE 0402LF
J 0
(-2250 4200);
DISPLAY 0.510638 (-2250 4200);
PAINT SKYBLUE (-2250 4200);
DISPLAY INVISIBLE (-2250 4200);
FORCEPROP 1 LAST WATTAGE 1/16W
J 2
(-2125 4225);
DISPLAY 0.510638 (-2125 4225);
PAINT SKYBLUE (-2125 4225);
DISPLAY INVISIBLE (-2125 4225);
FORCEPROP 1 LAST PART_NUMBER CS03322FB03
J 0
(-2325 4175);
DISPLAY 0.510638 (-2325 4175);
PAINT WHITE (-2325 4175);
DISPLAY INVISIBLE (-2325 4175);
FORCEPROP 1 LAST TOLERANCE 1%
J 0
(-2225 4250);
DISPLAY 0.510638 (-2225 4250);
PAINT SKYBLUE (-2225 4250);
DISPLAY INVISIBLE (-2225 4250);
FORCEPROP 1 LAST LOCATION R537
J 0
(-2475 4300);
DISPLAY 0.702128 (-2475 4300);
PAINT YELLOW (-2475 4300);
FORCEPROP 1 LASTPIN (-2350 4300) $PN 1
J 0
(-2338 4312);
DISPLAY 0.787234 (-2338 4312);
PAINT MONO (-2338 4312);
FORCEPROP 1 LASTPIN (-2150 4300) $PN 2
J 0
(-2188 4312);
DISPLAY 0.787234 (-2188 4312);
PAINT MONO (-2188 4312);
FORCEPROP 0 LAST $SEC 1
J 0
(-2475 4350);
DISPLAY 0.680851 (-2475 4350);
PAINT MONO (-2475 4350);
DISPLAY INVISIBLE (-2475 4350);
FORCEPROP 0 LAST CDS_SEC 1
J 0
(-2475 4350);
DISPLAY 0.680851 (-2475 4350);
DISPLAY INVISIBLE (-2475 4350);
FORCEADD Q_RES..1
(-2250 4650);
FORCEPROP 1 LAST VALUE 33.2
J 2
(-2025 4650);
DISPLAY 0.510638 (-2025 4650);
PAINT SKYBLUE (-2025 4650);
FORCEPROP 1 LAST MATERIAL EMPTY
J 0
(-2000 4650);
DISPLAY 0.510638 (-2000 4650);
PAINT SKYBLUE (-2000 4650);
FORCEPROP 1 LAST TOLERANCE 1%
J 0
(-2225 4600);
DISPLAY 0.510638 (-2225 4600);
PAINT SKYBLUE (-2225 4600);
DISPLAY INVISIBLE (-2225 4600);
FORCEPROP 1 LAST PART_NUMBER CS03322FB03
J 0
(-2325 4525);
DISPLAY 0.510638 (-2325 4525);
PAINT WHITE (-2325 4525);
DISPLAY INVISIBLE (-2325 4525);
FORCEPROP 1 LAST WATTAGE 1/16W
J 2
(-2125 4575);
DISPLAY 0.510638 (-2125 4575);
PAINT SKYBLUE (-2125 4575);
DISPLAY INVISIBLE (-2125 4575);
FORCEPROP 1 LAST PACK_TYPE 0402LF
J 0
(-2250 4550);
DISPLAY 0.510638 (-2250 4550);
PAINT SKYBLUE (-2250 4550);
DISPLAY INVISIBLE (-2250 4550);
FORCEPROP 1 LAST PATH I146
J 0
(-2300 4800);
DISPLAY 0.978723 (-2300 4800);
PAINT WHITE (-2300 4800);
DISPLAY INVISIBLE (-2300 4800);
FORCEPROP 2 LAST CDS_LIB pure_quanta
J 0
(-2250 4650);
DISPLAY INVISIBLE (-2250 4650);
FORCEPROP 1 LAST LOCATION R531
J 0
(-2475 4650);
DISPLAY 0.702128 (-2475 4650);
PAINT YELLOW (-2475 4650);
FORCEPROP 1 LASTPIN (-2350 4650) $PN 1
J 0
(-2338 4662);
DISPLAY 0.787234 (-2338 4662);
PAINT MONO (-2338 4662);
FORCEPROP 1 LASTPIN (-2150 4650) $PN 2
J 0
(-2188 4662);
DISPLAY 0.787234 (-2188 4662);
PAINT MONO (-2188 4662);
FORCEPROP 0 LAST $SEC 1
J 0
(-2475 4700);
DISPLAY 0.680851 (-2475 4700);
PAINT MONO (-2475 4700);
DISPLAY INVISIBLE (-2475 4700);
FORCEPROP 0 LAST CDS_SEC 1
J 0
(-2475 4700);
DISPLAY 0.680851 (-2475 4700);
DISPLAY INVISIBLE (-2475 4700);
FORCEADD Q_RES..1
(-2250 4750);
FORCEPROP 1 LAST MATERIAL EMPTY
J 0
(-2000 4750);
DISPLAY 0.510638 (-2000 4750);
PAINT SKYBLUE (-2000 4750);
FORCEPROP 1 LAST VALUE 33.2
J 2
(-2025 4750);
DISPLAY 0.510638 (-2025 4750);
PAINT SKYBLUE (-2025 4750);
FORCEPROP 1 LAST TOLERANCE 1%
J 0
(-2225 4700);
DISPLAY 0.510638 (-2225 4700);
PAINT SKYBLUE (-2225 4700);
DISPLAY INVISIBLE (-2225 4700);
FORCEPROP 1 LAST PART_NUMBER CS03322FB03
J 0
(-2325 4625);
DISPLAY 0.510638 (-2325 4625);
PAINT WHITE (-2325 4625);
DISPLAY INVISIBLE (-2325 4625);
FORCEPROP 1 LAST WATTAGE 1/16W
J 2
(-2125 4675);
DISPLAY 0.510638 (-2125 4675);
PAINT SKYBLUE (-2125 4675);
DISPLAY INVISIBLE (-2125 4675);
FORCEPROP 1 LAST PACK_TYPE 0402LF
J 0
(-2250 4650);
DISPLAY 0.510638 (-2250 4650);
PAINT SKYBLUE (-2250 4650);
DISPLAY INVISIBLE (-2250 4650);
FORCEPROP 1 LAST PATH I147
J 0
(-2300 4900);
DISPLAY 0.978723 (-2300 4900);
PAINT WHITE (-2300 4900);
DISPLAY INVISIBLE (-2300 4900);
FORCEPROP 2 LAST CDS_LIB pure_quanta
J 0
(-2250 4750);
DISPLAY INVISIBLE (-2250 4750);
FORCEPROP 1 LAST LOCATION R526
J 0
(-2475 4750);
DISPLAY 0.702128 (-2475 4750);
PAINT YELLOW (-2475 4750);
FORCEPROP 1 LASTPIN (-2350 4750) $PN 1
J 0
(-2338 4762);
DISPLAY 0.787234 (-2338 4762);
PAINT MONO (-2338 4762);
FORCEPROP 1 LASTPIN (-2150 4750) $PN 2
J 0
(-2188 4762);
DISPLAY 0.787234 (-2188 4762);
PAINT MONO (-2188 4762);
FORCEPROP 0 LAST $SEC 1
J 0
(-2475 4800);
DISPLAY 0.680851 (-2475 4800);
PAINT MONO (-2475 4800);
DISPLAY INVISIBLE (-2475 4800);
FORCEPROP 0 LAST CDS_SEC 1
J 0
(-2475 4800);
DISPLAY 0.680851 (-2475 4800);
DISPLAY INVISIBLE (-2475 4800);
FORCEADD Q_RES..1
(-2250 4800);
FORCEPROP 1 LAST MATERIAL CHIP
J 0
(-2000 4800);
DISPLAY 0.510638 (-2000 4800);
PAINT SKYBLUE (-2000 4800);
FORCEPROP 1 LAST VALUE 33.2
J 2
(-2025 4800);
DISPLAY 0.510638 (-2025 4800);
PAINT SKYBLUE (-2025 4800);
FORCEPROP 2 LAST CDS_LIB pure_quanta
J 0
(-2250 4800);
DISPLAY INVISIBLE (-2250 4800);
FORCEPROP 1 LAST PATH I148
J 0
(-2300 4950);
DISPLAY 0.978723 (-2300 4950);
PAINT WHITE (-2300 4950);
DISPLAY INVISIBLE (-2300 4950);
FORCEPROP 1 LAST PACK_TYPE 0402LF
J 0
(-2250 4700);
DISPLAY 0.510638 (-2250 4700);
PAINT SKYBLUE (-2250 4700);
DISPLAY INVISIBLE (-2250 4700);
FORCEPROP 1 LAST WATTAGE 1/16W
J 2
(-2125 4725);
DISPLAY 0.510638 (-2125 4725);
PAINT SKYBLUE (-2125 4725);
DISPLAY INVISIBLE (-2125 4725);
FORCEPROP 1 LAST PART_NUMBER CS03322FB03
J 0
(-2325 4675);
DISPLAY 0.510638 (-2325 4675);
PAINT WHITE (-2325 4675);
DISPLAY INVISIBLE (-2325 4675);
FORCEPROP 1 LAST TOLERANCE 1%
J 0
(-2225 4750);
DISPLAY 0.510638 (-2225 4750);
PAINT SKYBLUE (-2225 4750);
DISPLAY INVISIBLE (-2225 4750);
FORCEPROP 1 LAST LOCATION R691
J 0
(-2475 4800);
DISPLAY 0.702128 (-2475 4800);
PAINT YELLOW (-2475 4800);
FORCEPROP 1 LASTPIN (-2350 4800) $PN 1
J 0
(-2338 4812);
DISPLAY 0.787234 (-2338 4812);
PAINT MONO (-2338 4812);
FORCEPROP 1 LASTPIN (-2150 4800) $PN 2
J 0
(-2188 4812);
DISPLAY 0.787234 (-2188 4812);
PAINT MONO (-2188 4812);
FORCEPROP 0 LAST $SEC 1
J 0
(-2475 4850);
DISPLAY 0.680851 (-2475 4850);
PAINT MONO (-2475 4850);
DISPLAY INVISIBLE (-2475 4850);
FORCEPROP 0 LAST CDS_SEC 1
J 0
(-2475 4850);
DISPLAY 0.680851 (-2475 4850);
DISPLAY INVISIBLE (-2475 4850);
FORCEADD Q_RES..1
(-2250 4900);
FORCEPROP 1 LAST MATERIAL CHIP
J 0
(-2000 4900);
DISPLAY 0.510638 (-2000 4900);
PAINT SKYBLUE (-2000 4900);
FORCEPROP 1 LAST VALUE 33.2
J 2
(-2025 4900);
DISPLAY 0.510638 (-2025 4900);
PAINT SKYBLUE (-2025 4900);
FORCEPROP 2 LAST CDS_LIB pure_quanta
J 0
(-2250 4900);
DISPLAY INVISIBLE (-2250 4900);
FORCEPROP 1 LAST PATH I149
J 0
(-2300 5050);
DISPLAY 0.978723 (-2300 5050);
PAINT WHITE (-2300 5050);
DISPLAY INVISIBLE (-2300 5050);
FORCEPROP 1 LAST PACK_TYPE 0402LF
J 0
(-2250 4800);
DISPLAY 0.510638 (-2250 4800);
PAINT SKYBLUE (-2250 4800);
DISPLAY INVISIBLE (-2250 4800);
FORCEPROP 1 LAST WATTAGE 1/16W
J 2
(-2125 4825);
DISPLAY 0.510638 (-2125 4825);
PAINT SKYBLUE (-2125 4825);
DISPLAY INVISIBLE (-2125 4825);
FORCEPROP 1 LAST PART_NUMBER CS03322FB03
J 0
(-2325 4775);
DISPLAY 0.510638 (-2325 4775);
PAINT WHITE (-2325 4775);
DISPLAY INVISIBLE (-2325 4775);
FORCEPROP 1 LAST TOLERANCE 1%
J 0
(-2225 4850);
DISPLAY 0.510638 (-2225 4850);
PAINT SKYBLUE (-2225 4850);
DISPLAY INVISIBLE (-2225 4850);
FORCEPROP 1 LAST LOCATION R690
J 0
(-2475 4900);
DISPLAY 0.702128 (-2475 4900);
PAINT YELLOW (-2475 4900);
FORCEPROP 1 LASTPIN (-2350 4900) $PN 1
J 0
(-2338 4912);
DISPLAY 0.787234 (-2338 4912);
PAINT MONO (-2338 4912);
FORCEPROP 1 LASTPIN (-2150 4900) $PN 2
J 0
(-2188 4912);
DISPLAY 0.787234 (-2188 4912);
PAINT MONO (-2188 4912);
FORCEPROP 0 LAST $SEC 1
J 0
(-2475 4950);
DISPLAY 0.680851 (-2475 4950);
PAINT MONO (-2475 4950);
DISPLAY INVISIBLE (-2475 4950);
FORCEPROP 0 LAST CDS_SEC 1
J 0
(-2475 4950);
DISPLAY 0.680851 (-2475 4950);
DISPLAY INVISIBLE (-2475 4950);
FORCEADD OFFPAGE..4
(-775 4900);
FORCEPROP 2 LAST $XR2 13 
J 0
(-409 4900);
DISPLAY 0.638298 (-409 4900);
PAINT MONO (-409 4900);
FORCEPROP 2 LAST $XR1 11 
J 0
(-499 4900);
DISPLAY 0.638298 (-499 4900);
PAINT MONO (-499 4900);
FORCEPROP 2 LAST $XR0 10 
J 0
(-589 4900);
DISPLAY 0.638298 (-589 4900);
PAINT MONO (-589 4900);
FORCEPROP 1 LAST COMMENT_BODY TRUE
J 0
(-800 4800);
DISPLAY 0.872340 (-800 4800);
PAINT PEACH (-800 4800);
DISPLAY INVISIBLE (-800 4800);
FORCEPROP 1 LAST OFFPAGE TRUE
J 0
(-450 4775);
DISPLAY 0.872340 (-450 4775);
PAINT GREEN (-450 4775);
DISPLAY INVISIBLE (-450 4775);
FORCEPROP 2 LAST CDS_LIB standard
J 0
(-775 4900);
DISPLAY INVISIBLE (-775 4900);
FORCEPROP 2 LAST PATH I15
J 0
(-400 4950);
DISPLAY 0.680851 (-400 4950);
DISPLAY INVISIBLE (-400 4950);
FORCEADD Q_DIODE..1
R 2
(-1825 3200);
FORCEPROP 1 LAST PART_NUMBER BC000340033
J 2
(-1750 3330);
DISPLAY 0.723404 (-1750 3330);
PAINT GREEN (-1750 3330);
FORCEPROP 1 LAST MATERIAL EMPTY
J 2
(-1750 3275);
DISPLAY 0.723404 (-1750 3275);
PAINT GREEN (-1750 3275);
FORCEPROP 2 LAST VALUE SDMK0340L-7-F
J 2
(-1725 3425);
DISPLAY 0.680851 (-1725 3425);
FORCEPROP 0 LAST PACK_TYPE SMLF
J 2
(-1750 3425);
DISPLAY 0.680851 (-1750 3425);
DISPLAY INVISIBLE (-1750 3425);
FORCEPROP 1 LAST NEEDS_NO_SIZE TRUE
J 2
(-1825 3200);
DISPLAY 0.468085 (-1825 3200);
PAINT GREEN (-1825 3200);
DISPLAY INVISIBLE (-1825 3200);
FORCEPROP 1 LAST PIN_NAMES_ROTATE True
J 2
(-1750 3360);
DISPLAY 0.255319 (-1750 3360);
PAINT GREEN (-1750 3360);
DISPLAY INVISIBLE (-1750 3360);
FORCEPROP 1 LAST PATH I150
J 2
(-1925 3280);
DISPLAY 0.723404 (-1925 3280);
PAINT GREEN (-1925 3280);
DISPLAY INVISIBLE (-1925 3280);
FORCEPROP 2 LAST CDS_LIB pure_quanta
J 2
(-1825 3200);
DISPLAY INVISIBLE (-1825 3200);
FORCEPROP 1 LAST $LOCATION D23
J 2
(-1750 3385);
DISPLAY 0.723404 (-1750 3385);
PAINT GREEN (-1750 3385);
FORCEPROP 0 LASTPIN (-1700 3200) $PN 1
J 0
(-1690 3210);
DISPLAY 0.680851 (-1690 3210);
PAINT MONO (-1690 3210);
FORCEPROP 0 LASTPIN (-1950 3200) $PN 2
J 2
(-1960 3210);
DISPLAY 0.680851 (-1960 3210);
PAINT MONO (-1960 3210);
FORCEPROP 0 LAST CDS_LOCATION D23
J 0
(-1725 3475);
DISPLAY 0.680851 (-1725 3475);
DISPLAY INVISIBLE (-1725 3475);
FORCEPROP 0 LAST $SEC 1
J 0
(-1725 3475);
DISPLAY 0.680851 (-1725 3475);
PAINT MONO (-1725 3475);
DISPLAY INVISIBLE (-1725 3475);
FORCEPROP 0 LAST CDS_SEC 1
J 0
(-1725 3475);
DISPLAY 0.680851 (-1725 3475);
DISPLAY INVISIBLE (-1725 3475);
FORCEADD Q_RES..1
(-2950 1775);
FORCEPROP 1 LAST VALUE 4.7K
J 0
(-2875 1775);
DISPLAY 0.510638 (-2875 1775);
PAINT SKYBLUE (-2875 1775);
FORCEPROP 1 LAST MATERIAL CHIP
J 0
(-2750 1775);
DISPLAY 0.510638 (-2750 1775);
PAINT SKYBLUE (-2750 1775);
FORCEPROP 2 LAST CDS_LIB pure_quanta
J 0
(-2950 1775);
DISPLAY INVISIBLE (-2950 1775);
FORCEPROP 1 LAST PATH I151
J 0
(-3000 1925);
DISPLAY 0.978723 (-3000 1925);
PAINT WHITE (-3000 1925);
DISPLAY INVISIBLE (-3000 1925);
FORCEPROP 1 LAST PART_NUMBER CS24702FB06
J 0
(-3000 1875);
DISPLAY 0.510638 (-3000 1875);
PAINT WHITE (-3000 1875);
DISPLAY INVISIBLE (-3000 1875);
FORCEPROP 1 LAST PACK_TYPE 0402LF
J 0
(-2700 1625);
DISPLAY 0.510638 (-2700 1625);
PAINT SKYBLUE (-2700 1625);
DISPLAY INVISIBLE (-2700 1625);
FORCEPROP 1 LAST WATTAGE 1/16W
J 2
(-2975 1625);
DISPLAY 0.510638 (-2975 1625);
PAINT SKYBLUE (-2975 1625);
DISPLAY INVISIBLE (-2975 1625);
FORCEPROP 1 LAST TOLERANCE 1%
J 0
(-2950 1675);
DISPLAY 0.510638 (-2950 1675);
PAINT SKYBLUE (-2950 1675);
DISPLAY INVISIBLE (-2950 1675);
FORCEPROP 1 LAST $LOCATION R886
J 0
(-3125 1775);
DISPLAY 0.702128 (-3125 1775);
PAINT YELLOW (-3125 1775);
FORCEPROP 1 LASTPIN (-3050 1775) $PN 1
J 0
(-3038 1787);
DISPLAY 0.787234 (-3038 1787);
PAINT MONO (-3038 1787);
FORCEPROP 1 LASTPIN (-2850 1775) $PN 2
J 0
(-2888 1787);
DISPLAY 0.787234 (-2888 1787);
PAINT MONO (-2888 1787);
FORCEPROP 0 LAST CDS_LOCATION R886
J 0
(-3125 1825);
DISPLAY 0.680851 (-3125 1825);
DISPLAY INVISIBLE (-3125 1825);
FORCEPROP 0 LAST $SEC 1
J 0
(-3125 1825);
DISPLAY 0.680851 (-3125 1825);
PAINT MONO (-3125 1825);
DISPLAY INVISIBLE (-3125 1825);
FORCEPROP 0 LAST CDS_SEC 1
J 0
(-3125 1825);
DISPLAY 0.680851 (-3125 1825);
DISPLAY INVISIBLE (-3125 1825);
FORCEADD VCCAUX15..1
(-3175 1900);
FORCEPROP 3 LASTPIN (-3175 1850) SIG_NAME P3V3_AUX\g
J 0
(-3165 1860);
DISPLAY 0.659574 (-3165 1860);
PAINT MONO (-3165 1860);
DISPLAY INVISIBLE (-3165 1860);
FORCEPROP 1 LAST HDL_POWER P3V3_AUX
J 1
(-3175 1950);
DISPLAY 0.702128 (-3175 1950);
PAINT GREEN (-3175 1950);
FORCEPROP 1 LAST PATH I152
J 0
(-3125 1925);
DISPLAY 0.872340 (-3125 1925);
PAINT AQUA (-3125 1925);
DISPLAY INVISIBLE (-3125 1925);
FORCEPROP 2 LAST CDS_LIB logical_power
J 0
(-3175 1900);
DISPLAY INVISIBLE (-3175 1900);
FORCEADD OFFPAGE..5
(-2325 3350);
FORCEPROP 2 LAST CDS_LIB standard
J 0
(-2325 3350);
DISPLAY INVISIBLE (-2325 3350);
FORCEPROP 2 LAST PATH I153
J 0
(-2275 3425);
DISPLAY 0.680851 (-2275 3425);
DISPLAY INVISIBLE (-2275 3425);
FORCEPROP 1 LAST COMMENT_BODY TRUE
J 0
(-2225 3275);
DISPLAY 0.872340 (-2225 3275);
PAINT PEACH (-2225 3275);
DISPLAY INVISIBLE (-2225 3275);
FORCEPROP 1 LAST OFFPAGE TRUE
J 0
(-2000 3225);
DISPLAY 0.872340 (-2000 3225);
PAINT GREEN (-2000 3225);
DISPLAY INVISIBLE (-2000 3225);
FORCEADD OFFPAGE..2
(-1900 1775);
FORCEPROP 2 LAST CDS_LIB standard
J 0
(-1900 1775);
DISPLAY INVISIBLE (-1900 1775);
FORCEPROP 2 LAST PATH I154
J 0
(-1725 1850);
DISPLAY 0.680851 (-1725 1850);
DISPLAY INVISIBLE (-1725 1850);
FORCEPROP 1 LAST COMMENT_BODY TRUE
J 0
(-1945 1680);
DISPLAY 0.872340 (-1945 1680);
PAINT PEACH (-1945 1680);
DISPLAY INVISIBLE (-1945 1680);
FORCEPROP 1 LAST OFFPAGE TRUE
J 0
(-1575 1650);
DISPLAY 0.872340 (-1575 1650);
PAINT GREEN (-1575 1650);
DISPLAY INVISIBLE (-1575 1650);
FORCEADD OFFPAGE..3
(-775 4750);
FORCEPROP 2 LAST $XR0 42 
J 0
(-561 4750);
DISPLAY 0.638298 (-561 4750);
PAINT MONO (-561 4750);
FORCEPROP 1 LAST COMMENT_BODY TRUE
J 0
(-825 4650);
DISPLAY 0.872340 (-825 4650);
PAINT GREEN (-825 4650);
DISPLAY INVISIBLE (-825 4650);
FORCEPROP 1 LAST OFFPAGE TRUE
J 0
(-450 4625);
DISPLAY 0.872340 (-450 4625);
DISPLAY INVISIBLE (-450 4625);
FORCEPROP 2 LAST CDS_LIB standard
J 0
(-775 4750);
DISPLAY INVISIBLE (-775 4750);
FORCEPROP 2 LAST PATH I16
J 0
(-450 4800);
DISPLAY 0.680851 (-450 4800);
DISPLAY INVISIBLE (-450 4800);
FORCEADD OFFPAGE..4
(-775 4800);
FORCEPROP 2 LAST $XR2 10 
J 0
(-409 4800);
DISPLAY 0.638298 (-409 4800);
PAINT MONO (-409 4800);
FORCEPROP 2 LAST $XR1 13 
J 0
(-499 4800);
DISPLAY 0.638298 (-499 4800);
PAINT MONO (-499 4800);
FORCEPROP 2 LAST $XR0 11 
J 0
(-589 4800);
DISPLAY 0.638298 (-589 4800);
PAINT MONO (-589 4800);
FORCEPROP 1 LAST COMMENT_BODY TRUE
J 0
(-800 4700);
DISPLAY 0.872340 (-800 4700);
PAINT GREEN (-800 4700);
DISPLAY INVISIBLE (-800 4700);
FORCEPROP 1 LAST OFFPAGE TRUE
J 0
(-450 4675);
DISPLAY 0.872340 (-450 4675);
DISPLAY INVISIBLE (-450 4675);
FORCEPROP 2 LAST CDS_LIB standard
J 0
(-775 4800);
DISPLAY INVISIBLE (-775 4800);
FORCEPROP 2 LAST PATH I17
J 0
(-400 4850);
DISPLAY 0.680851 (-400 4850);
DISPLAY INVISIBLE (-400 4850);
FORCEADD OFFPAGE..3
(-775 4650);
FORCEPROP 2 LAST $XR0 42 
J 0
(-561 4650);
DISPLAY 0.638298 (-561 4650);
PAINT MONO (-561 4650);
FORCEPROP 1 LAST COMMENT_BODY TRUE
J 0
(-825 4550);
DISPLAY 0.872340 (-825 4550);
PAINT GREEN (-825 4550);
DISPLAY INVISIBLE (-825 4550);
FORCEPROP 1 LAST OFFPAGE TRUE
J 0
(-450 4525);
DISPLAY 0.872340 (-450 4525);
DISPLAY INVISIBLE (-450 4525);
FORCEPROP 2 LAST CDS_LIB standard
J 0
(-775 4650);
DISPLAY INVISIBLE (-775 4650);
FORCEPROP 2 LAST PATH I18
J 0
(-450 4700);
DISPLAY 0.680851 (-450 4700);
DISPLAY INVISIBLE (-450 4700);
FORCEADD Q_RES..1
(-7300 4950);
FORCEPROP 1 LAST MATERIAL CHIP
J 0
(-7100 4950);
DISPLAY 0.510638 (-7100 4950);
PAINT SKYBLUE (-7100 4950);
FORCEPROP 1 LAST VALUE 0
J 2
(-7150 4950);
DISPLAY 0.510638 (-7150 4950);
PAINT SKYBLUE (-7150 4950);
FORCEPROP 1 LAST PATH I2
J 0
(-7350 5100);
DISPLAY 0.978723 (-7350 5100);
PAINT WHITE (-7350 5100);
DISPLAY INVISIBLE (-7350 5100);
FORCEPROP 1 LAST PART_NUMBER CS00002JB13
J 0
(-7400 5025);
DISPLAY 0.510638 (-7400 5025);
PAINT WHITE (-7400 5025);
DISPLAY INVISIBLE (-7400 5025);
FORCEPROP 2 LAST CDS_LIB pure_quanta
J 0
(-7300 4950);
DISPLAY INVISIBLE (-7300 4950);
FORCEPROP 1 LAST TOLERANCE 5%
J 0
(-7375 5050);
DISPLAY 0.510638 (-7375 5050);
PAINT SKYBLUE (-7375 5050);
DISPLAY INVISIBLE (-7375 5050);
FORCEPROP 1 LAST WATTAGE 1/16W
J 2
(-6950 5050);
DISPLAY 0.510638 (-6950 5050);
PAINT SKYBLUE (-6950 5050);
DISPLAY INVISIBLE (-6950 5050);
FORCEPROP 1 LAST PACK_TYPE 0402LF
J 0
(-7325 5000);
DISPLAY 0.510638 (-7325 5000);
PAINT SKYBLUE (-7325 5000);
DISPLAY INVISIBLE (-7325 5000);
FORCEPROP 1 LAST LOCATION R453
J 0
(-7500 4950);
DISPLAY 0.702128 (-7500 4950);
PAINT YELLOW (-7500 4950);
FORCEPROP 0 LAST $SEC 1
J 0
(-7450 5000);
DISPLAY 0.680851 (-7450 5000);
PAINT MONO (-7450 5000);
DISPLAY INVISIBLE (-7450 5000);
FORCEPROP 0 LAST CDS_SEC 1
J 0
(-7450 5000);
DISPLAY 1.021277 (-7450 5000);
DISPLAY INVISIBLE (-7450 5000);
FORCEPROP 1 LASTPIN (-7400 4950) $PN 1
J 0
(-7388 4962);
DISPLAY 0.808511 (-7388 4962);
PAINT WHITE (-7388 4962);
DISPLAY INVISIBLE (-7388 4962);
FORCEPROP 1 LASTPIN (-7200 4950) $PN 2
J 0
(-7238 4962);
DISPLAY 0.808511 (-7238 4962);
PAINT WHITE (-7238 4962);
DISPLAY INVISIBLE (-7238 4962);
FORCEADD OFFPAGE..3
(-775 4350);
FORCEPROP 2 LAST $XR0 42 
J 0
(-561 4350);
DISPLAY 0.638298 (-561 4350);
PAINT MONO (-561 4350);
FORCEPROP 1 LAST COMMENT_BODY TRUE
J 0
(-825 4250);
DISPLAY 0.872340 (-825 4250);
PAINT GREEN (-825 4250);
DISPLAY INVISIBLE (-825 4250);
FORCEPROP 1 LAST OFFPAGE TRUE
J 0
(-450 4225);
DISPLAY 0.872340 (-450 4225);
DISPLAY INVISIBLE (-450 4225);
FORCEPROP 2 LAST CDS_LIB standard
J 0
(-775 4350);
DISPLAY INVISIBLE (-775 4350);
FORCEPROP 2 LAST PATH I21
J 0
(-450 4400);
DISPLAY 0.680851 (-450 4400);
DISPLAY INVISIBLE (-450 4400);
FORCEADD OFFPAGE..3
(-775 4300);
FORCEPROP 2 LAST $XR0 42 
J 0
(-561 4300);
DISPLAY 0.638298 (-561 4300);
PAINT MONO (-561 4300);
FORCEPROP 1 LAST COMMENT_BODY TRUE
J 0
(-825 4200);
DISPLAY 0.872340 (-825 4200);
PAINT GREEN (-825 4200);
DISPLAY INVISIBLE (-825 4200);
FORCEPROP 1 LAST OFFPAGE TRUE
J 0
(-450 4175);
DISPLAY 0.872340 (-450 4175);
DISPLAY INVISIBLE (-450 4175);
FORCEPROP 2 LAST CDS_LIB standard
J 0
(-775 4300);
DISPLAY INVISIBLE (-775 4300);
FORCEPROP 2 LAST PATH I23
J 0
(-450 4350);
DISPLAY 0.680851 (-450 4350);
DISPLAY INVISIBLE (-450 4350);
FORCEADD Q_RES..1
(-7300 4900);
FORCEPROP 1 LAST MATERIAL CHIP
J 0
(-7100 4900);
DISPLAY 0.510638 (-7100 4900);
PAINT SKYBLUE (-7100 4900);
FORCEPROP 1 LAST VALUE 0
J 2
(-7150 4900);
DISPLAY 0.510638 (-7150 4900);
PAINT SKYBLUE (-7150 4900);
FORCEPROP 1 LAST PATH I3
J 0
(-7350 5050);
DISPLAY 0.978723 (-7350 5050);
PAINT WHITE (-7350 5050);
DISPLAY INVISIBLE (-7350 5050);
FORCEPROP 1 LAST PART_NUMBER CS00002JB13
J 0
(-7400 4975);
DISPLAY 0.510638 (-7400 4975);
PAINT WHITE (-7400 4975);
DISPLAY INVISIBLE (-7400 4975);
FORCEPROP 2 LAST CDS_LIB pure_quanta
J 0
(-7300 4900);
DISPLAY INVISIBLE (-7300 4900);
FORCEPROP 1 LAST TOLERANCE 5%
J 0
(-7375 5000);
DISPLAY 0.510638 (-7375 5000);
PAINT SKYBLUE (-7375 5000);
DISPLAY INVISIBLE (-7375 5000);
FORCEPROP 1 LAST WATTAGE 1/16W
J 2
(-6950 5000);
DISPLAY 0.510638 (-6950 5000);
PAINT SKYBLUE (-6950 5000);
DISPLAY INVISIBLE (-6950 5000);
FORCEPROP 1 LAST PACK_TYPE 0402LF
J 0
(-7325 4950);
DISPLAY 0.510638 (-7325 4950);
PAINT SKYBLUE (-7325 4950);
DISPLAY INVISIBLE (-7325 4950);
FORCEPROP 1 LAST LOCATION R454
J 0
(-7500 4900);
DISPLAY 0.702128 (-7500 4900);
PAINT YELLOW (-7500 4900);
FORCEPROP 0 LAST $SEC 1
J 0
(-7450 4950);
DISPLAY 0.680851 (-7450 4950);
PAINT MONO (-7450 4950);
DISPLAY INVISIBLE (-7450 4950);
FORCEPROP 0 LAST CDS_SEC 1
J 0
(-7450 4950);
DISPLAY 1.021277 (-7450 4950);
DISPLAY INVISIBLE (-7450 4950);
FORCEPROP 1 LASTPIN (-7400 4900) $PN 1
J 0
(-7388 4912);
DISPLAY 0.808511 (-7388 4912);
PAINT WHITE (-7388 4912);
DISPLAY INVISIBLE (-7388 4912);
FORCEPROP 1 LASTPIN (-7200 4900) $PN 2
J 0
(-7238 4912);
DISPLAY 0.808511 (-7238 4912);
PAINT WHITE (-7238 4912);
DISPLAY INVISIBLE (-7238 4912);
FORCEADD Q_RES..1
(-7300 4800);
FORCEPROP 1 LAST MATERIAL CHIP
J 0
(-7100 4800);
DISPLAY 0.510638 (-7100 4800);
PAINT SKYBLUE (-7100 4800);
FORCEPROP 1 LAST VALUE 0
J 2
(-7150 4800);
DISPLAY 0.510638 (-7150 4800);
PAINT SKYBLUE (-7150 4800);
FORCEPROP 1 LAST PACK_TYPE 0402LF
J 0
(-7325 4850);
DISPLAY 0.510638 (-7325 4850);
PAINT SKYBLUE (-7325 4850);
DISPLAY INVISIBLE (-7325 4850);
FORCEPROP 1 LAST WATTAGE 1/16W
J 2
(-6950 4900);
DISPLAY 0.510638 (-6950 4900);
PAINT SKYBLUE (-6950 4900);
DISPLAY INVISIBLE (-6950 4900);
FORCEPROP 1 LAST TOLERANCE 5%
J 0
(-7375 4900);
DISPLAY 0.510638 (-7375 4900);
PAINT SKYBLUE (-7375 4900);
DISPLAY INVISIBLE (-7375 4900);
FORCEPROP 2 LAST CDS_LIB pure_quanta
J 0
(-7300 4800);
DISPLAY INVISIBLE (-7300 4800);
FORCEPROP 1 LAST PART_NUMBER CS00002JB13
J 0
(-7400 4875);
DISPLAY 0.510638 (-7400 4875);
PAINT WHITE (-7400 4875);
DISPLAY INVISIBLE (-7400 4875);
FORCEPROP 1 LAST PATH I4
J 0
(-7350 4950);
DISPLAY 0.978723 (-7350 4950);
PAINT WHITE (-7350 4950);
DISPLAY INVISIBLE (-7350 4950);
FORCEPROP 1 LAST LOCATION R456
J 0
(-7500 4800);
DISPLAY 0.702128 (-7500 4800);
PAINT YELLOW (-7500 4800);
FORCEPROP 0 LAST $SEC 1
J 0
(-7450 4850);
DISPLAY 0.680851 (-7450 4850);
PAINT MONO (-7450 4850);
DISPLAY INVISIBLE (-7450 4850);
FORCEPROP 0 LAST CDS_SEC 1
J 0
(-7450 4850);
DISPLAY 1.021277 (-7450 4850);
DISPLAY INVISIBLE (-7450 4850);
FORCEPROP 1 LASTPIN (-7400 4800) $PN 1
J 0
(-7388 4812);
DISPLAY 0.808511 (-7388 4812);
PAINT WHITE (-7388 4812);
DISPLAY INVISIBLE (-7388 4812);
FORCEPROP 1 LASTPIN (-7200 4800) $PN 2
J 0
(-7238 4812);
DISPLAY 0.808511 (-7238 4812);
PAINT WHITE (-7238 4812);
DISPLAY INVISIBLE (-7238 4812);
FORCEADD Q_RES..1
(-7300 4750);
FORCEPROP 1 LAST MATERIAL CHIP
J 0
(-7100 4750);
DISPLAY 0.510638 (-7100 4750);
PAINT SKYBLUE (-7100 4750);
FORCEPROP 1 LAST VALUE 0
J 2
(-7150 4750);
DISPLAY 0.510638 (-7150 4750);
PAINT SKYBLUE (-7150 4750);
FORCEPROP 1 LAST PACK_TYPE 0402LF
J 0
(-7325 4800);
DISPLAY 0.510638 (-7325 4800);
PAINT SKYBLUE (-7325 4800);
DISPLAY INVISIBLE (-7325 4800);
FORCEPROP 1 LAST WATTAGE 1/16W
J 2
(-6950 4850);
DISPLAY 0.510638 (-6950 4850);
PAINT SKYBLUE (-6950 4850);
DISPLAY INVISIBLE (-6950 4850);
FORCEPROP 1 LAST TOLERANCE 5%
J 0
(-7375 4850);
DISPLAY 0.510638 (-7375 4850);
PAINT SKYBLUE (-7375 4850);
DISPLAY INVISIBLE (-7375 4850);
FORCEPROP 2 LAST CDS_LIB pure_quanta
J 0
(-7300 4750);
DISPLAY INVISIBLE (-7300 4750);
FORCEPROP 1 LAST PART_NUMBER CS00002JB13
J 0
(-7400 4825);
DISPLAY 0.510638 (-7400 4825);
PAINT WHITE (-7400 4825);
DISPLAY INVISIBLE (-7400 4825);
FORCEPROP 1 LAST PATH I5
J 0
(-7350 4900);
DISPLAY 0.978723 (-7350 4900);
PAINT WHITE (-7350 4900);
DISPLAY INVISIBLE (-7350 4900);
FORCEPROP 1 LAST LOCATION R457
J 0
(-7500 4750);
DISPLAY 0.702128 (-7500 4750);
PAINT YELLOW (-7500 4750);
FORCEPROP 0 LAST $SEC 1
J 0
(-7450 4800);
DISPLAY 0.680851 (-7450 4800);
PAINT MONO (-7450 4800);
DISPLAY INVISIBLE (-7450 4800);
FORCEPROP 0 LAST CDS_SEC 1
J 0
(-7450 4800);
DISPLAY 1.021277 (-7450 4800);
DISPLAY INVISIBLE (-7450 4800);
FORCEPROP 1 LASTPIN (-7400 4750) $PN 1
J 0
(-7388 4762);
DISPLAY 0.808511 (-7388 4762);
PAINT WHITE (-7388 4762);
DISPLAY INVISIBLE (-7388 4762);
FORCEPROP 1 LASTPIN (-7200 4750) $PN 2
J 0
(-7238 4762);
DISPLAY 0.808511 (-7238 4762);
PAINT WHITE (-7238 4762);
DISPLAY INVISIBLE (-7238 4762);
FORCEADD OFFPAGE..5
(-8550 3400);
FORCEPROP 2 LAST $XR2 27 
J 0
(-8954 3400);
DISPLAY 0.638298 (-8954 3400);
PAINT MONO (-8954 3400);
FORCEPROP 2 LAST $XR1 26 
J 0
(-8864 3400);
DISPLAY 0.638298 (-8864 3400);
PAINT MONO (-8864 3400);
FORCEPROP 2 LAST $XR0 15 
J 0
(-8774 3400);
DISPLAY 0.638298 (-8774 3400);
PAINT MONO (-8774 3400);
FORCEPROP 2 LAST CDS_LIB standard
J 0
(-8550 3400);
DISPLAY INVISIBLE (-8550 3400);
FORCEPROP 1 LAST OFFPAGE TRUE
J 0
(-8225 3275);
DISPLAY 0.872340 (-8225 3275);
DISPLAY INVISIBLE (-8225 3275);
FORCEPROP 1 LAST COMMENT_BODY TRUE
J 0
(-8450 3325);
DISPLAY 0.872340 (-8450 3325);
PAINT GREEN (-8450 3325);
DISPLAY INVISIBLE (-8450 3325);
FORCEPROP 2 LAST PATH I52
J 0
(-8800 3450);
DISPLAY 0.680851 (-8800 3450);
DISPLAY INVISIBLE (-8800 3450);
FORCEADD OFFPAGE..1
(-8550 3700);
FORCEPROP 2 LAST $XR0 13 
J 0
(-8771 3700);
DISPLAY 0.638298 (-8771 3700);
PAINT MONO (-8771 3700);
FORCEPROP 2 LAST $XR1 27 
J 0
(-8861 3700);
DISPLAY 0.638298 (-8861 3700);
PAINT MONO (-8861 3700);
FORCEPROP 2 LAST PATH I53
J 0
(-8800 3750);
DISPLAY 0.680851 (-8800 3750);
DISPLAY INVISIBLE (-8800 3750);
FORCEPROP 1 LAST COMMENT_BODY TRUE
J 0
(-8425 3600);
DISPLAY 0.872340 (-8425 3600);
PAINT PEACH (-8425 3600);
DISPLAY INVISIBLE (-8425 3600);
FORCEPROP 1 LAST OFFPAGE TRUE
J 0
(-8225 3575);
DISPLAY 0.872340 (-8225 3575);
PAINT GREEN (-8225 3575);
DISPLAY INVISIBLE (-8225 3575);
FORCEPROP 2 LAST CDS_LIB standard
J 0
(-8550 3700);
DISPLAY INVISIBLE (-8550 3700);
FORCEADD OFFPAGE..5
(-8550 3750);
FORCEPROP 2 LAST $XR0 15 
J 0
(-8774 3750);
DISPLAY 0.638298 (-8774 3750);
PAINT MONO (-8774 3750);
FORCEPROP 2 LAST PATH I54
J 0
(-8800 3800);
DISPLAY 0.680851 (-8800 3800);
DISPLAY INVISIBLE (-8800 3800);
FORCEPROP 1 LAST COMMENT_BODY TRUE
J 0
(-8450 3675);
DISPLAY 0.872340 (-8450 3675);
PAINT PEACH (-8450 3675);
DISPLAY INVISIBLE (-8450 3675);
FORCEPROP 1 LAST OFFPAGE TRUE
J 0
(-8225 3625);
DISPLAY 0.872340 (-8225 3625);
PAINT GREEN (-8225 3625);
DISPLAY INVISIBLE (-8225 3625);
FORCEPROP 2 LAST CDS_LIB standard
J 0
(-8550 3750);
DISPLAY INVISIBLE (-8550 3750);
FORCEADD OFFPAGE..5
(-8550 3850);
FORCEPROP 2 LAST $XR1 15 
J 0
(-8864 3850);
DISPLAY 0.638298 (-8864 3850);
PAINT MONO (-8864 3850);
FORCEPROP 2 LAST $XR0 27 
J 0
(-8774 3850);
DISPLAY 0.638298 (-8774 3850);
PAINT MONO (-8774 3850);
FORCEPROP 2 LAST CDS_LIB standard
J 0
(-8550 3850);
DISPLAY INVISIBLE (-8550 3850);
FORCEPROP 1 LAST OFFPAGE TRUE
J 0
(-8225 3725);
DISPLAY 0.872340 (-8225 3725);
DISPLAY INVISIBLE (-8225 3725);
FORCEPROP 1 LAST COMMENT_BODY TRUE
J 0
(-8450 3775);
DISPLAY 0.872340 (-8450 3775);
PAINT GREEN (-8450 3775);
DISPLAY INVISIBLE (-8450 3775);
FORCEPROP 2 LAST PATH I55
J 0
(-8800 3900);
DISPLAY 0.680851 (-8800 3900);
DISPLAY INVISIBLE (-8800 3900);
FORCEADD OFFPAGE..5
(-8550 4000);
FORCEPROP 2 LAST $XR0 42 
J 0
(-8774 4000);
DISPLAY 0.638298 (-8774 4000);
PAINT MONO (-8774 4000);
FORCEPROP 2 LAST $XR1 15 
J 0
(-8864 4000);
DISPLAY 0.638298 (-8864 4000);
PAINT MONO (-8864 4000);
FORCEPROP 2 LAST CDS_LIB standard
J 0
(-8550 4000);
DISPLAY INVISIBLE (-8550 4000);
FORCEPROP 1 LAST OFFPAGE TRUE
J 0
(-8225 3875);
DISPLAY 0.872340 (-8225 3875);
PAINT GREEN (-8225 3875);
DISPLAY INVISIBLE (-8225 3875);
FORCEPROP 1 LAST COMMENT_BODY TRUE
J 0
(-8450 3925);
DISPLAY 0.872340 (-8450 3925);
PAINT PEACH (-8450 3925);
DISPLAY INVISIBLE (-8450 3925);
FORCEPROP 2 LAST PATH I57
J 0
(-8800 4050);
DISPLAY 0.680851 (-8800 4050);
DISPLAY INVISIBLE (-8800 4050);
FORCEADD OFFPAGE..5
(-8550 4150);
FORCEPROP 2 LAST $XR0 13 
J 0
(-8774 4150);
DISPLAY 0.638298 (-8774 4150);
PAINT MONO (-8774 4150);
FORCEPROP 2 LAST CDS_LIB standard
J 0
(-8550 4150);
DISPLAY INVISIBLE (-8550 4150);
FORCEPROP 1 LAST OFFPAGE TRUE
J 0
(-8225 4025);
DISPLAY 0.872340 (-8225 4025);
PAINT GREEN (-8225 4025);
DISPLAY INVISIBLE (-8225 4025);
FORCEPROP 1 LAST COMMENT_BODY TRUE
J 0
(-8450 4075);
DISPLAY 0.872340 (-8450 4075);
PAINT PEACH (-8450 4075);
DISPLAY INVISIBLE (-8450 4075);
FORCEPROP 2 LAST PATH I58
J 0
(-8800 4200);
DISPLAY 0.680851 (-8800 4200);
DISPLAY INVISIBLE (-8800 4200);
FORCEADD OFFPAGE..5
(-8550 4200);
FORCEPROP 2 LAST $XR0 15 
J 0
(-8774 4200);
DISPLAY 0.638298 (-8774 4200);
PAINT MONO (-8774 4200);
FORCEPROP 2 LAST CDS_LIB standard
J 0
(-8550 4200);
DISPLAY INVISIBLE (-8550 4200);
FORCEPROP 1 LAST OFFPAGE TRUE
J 0
(-8225 4075);
DISPLAY 0.872340 (-8225 4075);
PAINT GREEN (-8225 4075);
DISPLAY INVISIBLE (-8225 4075);
FORCEPROP 1 LAST COMMENT_BODY TRUE
J 0
(-8450 4125);
DISPLAY 0.872340 (-8450 4125);
PAINT PEACH (-8450 4125);
DISPLAY INVISIBLE (-8450 4125);
FORCEPROP 2 LAST PATH I59
J 0
(-8800 4250);
DISPLAY 0.680851 (-8800 4250);
DISPLAY INVISIBLE (-8800 4250);
FORCEADD OFFPAGE..5
(-8550 4050);
FORCEPROP 2 LAST $XR0 10 
J 0
(-8774 4050);
DISPLAY 0.638298 (-8774 4050);
PAINT MONO (-8774 4050);
FORCEPROP 2 LAST CDS_LIB standard
J 0
(-8550 4050);
DISPLAY INVISIBLE (-8550 4050);
FORCEPROP 1 LAST OFFPAGE TRUE
J 0
(-8225 3925);
DISPLAY 0.872340 (-8225 3925);
PAINT GREEN (-8225 3925);
DISPLAY INVISIBLE (-8225 3925);
FORCEPROP 1 LAST COMMENT_BODY TRUE
J 0
(-8450 3975);
DISPLAY 0.872340 (-8450 3975);
PAINT PEACH (-8450 3975);
DISPLAY INVISIBLE (-8450 3975);
FORCEPROP 2 LAST PATH I60
J 0
(-8800 4100);
DISPLAY 0.680851 (-8800 4100);
DISPLAY INVISIBLE (-8800 4100);
FORCEADD OFFPAGE..5
(-8550 4300);
FORCEPROP 2 LAST $XR1 13 
J 0
(-8864 4300);
DISPLAY 0.638298 (-8864 4300);
PAINT MONO (-8864 4300);
FORCEPROP 2 LAST $XR0 11 
J 0
(-8774 4300);
DISPLAY 0.638298 (-8774 4300);
PAINT MONO (-8774 4300);
FORCEPROP 2 LAST CDS_LIB standard
J 0
(-8550 4300);
DISPLAY INVISIBLE (-8550 4300);
FORCEPROP 1 LAST OFFPAGE TRUE
J 0
(-8225 4175);
DISPLAY 0.872340 (-8225 4175);
PAINT GREEN (-8225 4175);
DISPLAY INVISIBLE (-8225 4175);
FORCEPROP 1 LAST COMMENT_BODY TRUE
J 0
(-8450 4225);
DISPLAY 0.872340 (-8450 4225);
PAINT PEACH (-8450 4225);
DISPLAY INVISIBLE (-8450 4225);
FORCEPROP 2 LAST PATH I61
J 0
(-8800 4350);
DISPLAY 0.680851 (-8800 4350);
DISPLAY INVISIBLE (-8800 4350);
FORCEADD OFFPAGE..1
(-8550 4450);
FORCEPROP 2 LAST $XR1 13 
J 0
(-8861 4450);
DISPLAY 0.638298 (-8861 4450);
PAINT MONO (-8861 4450);
FORCEPROP 2 LAST $XR0 11 
J 0
(-8771 4450);
DISPLAY 0.638298 (-8771 4450);
PAINT MONO (-8771 4450);
FORCEPROP 2 LAST $XR3 36 
J 0
(-9041 4450);
DISPLAY 0.638298 (-9041 4450);
PAINT MONO (-9041 4450);
FORCEPROP 2 LAST $XR2 10 
J 0
(-8951 4450);
DISPLAY 0.638298 (-8951 4450);
PAINT MONO (-8951 4450);
FORCEPROP 2 LAST CDS_LIB standard
J 0
(-8550 4450);
DISPLAY INVISIBLE (-8550 4450);
FORCEPROP 2 LAST PATH I62
J 0
(-8800 4500);
DISPLAY 0.680851 (-8800 4500);
DISPLAY INVISIBLE (-8800 4500);
FORCEPROP 1 LAST COMMENT_BODY TRUE
J 0
(-8425 4350);
DISPLAY 0.872340 (-8425 4350);
PAINT GREEN (-8425 4350);
DISPLAY INVISIBLE (-8425 4350);
FORCEPROP 1 LAST OFFPAGE TRUE
J 0
(-8225 4325);
DISPLAY 0.872340 (-8225 4325);
DISPLAY INVISIBLE (-8225 4325);
FORCEADD OFFPAGE..1
(-8550 4350);
FORCEPROP 2 LAST $XR0 13 
J 0
(-8771 4350);
DISPLAY 0.638298 (-8771 4350);
PAINT MONO (-8771 4350);
FORCEPROP 2 LAST CDS_LIB standard
J 0
(-8550 4350);
DISPLAY INVISIBLE (-8550 4350);
FORCEPROP 1 LAST OFFPAGE TRUE
J 0
(-8225 4225);
DISPLAY 0.872340 (-8225 4225);
DISPLAY INVISIBLE (-8225 4225);
FORCEPROP 1 LAST COMMENT_BODY TRUE
J 0
(-8425 4250);
DISPLAY 0.872340 (-8425 4250);
PAINT GREEN (-8425 4250);
DISPLAY INVISIBLE (-8425 4250);
FORCEPROP 2 LAST PATH I63
J 0
(-8750 4400);
DISPLAY 0.680851 (-8750 4400);
DISPLAY INVISIBLE (-8750 4400);
FORCEADD Q_RES..1
(-7300 3400);
FORCEPROP 1 LAST MATERIAL CHIP
J 0
(-7100 3400);
DISPLAY 0.510638 (-7100 3400);
PAINT SKYBLUE (-7100 3400);
FORCEPROP 1 LAST VALUE 0
J 2
(-7150 3400);
DISPLAY 0.510638 (-7150 3400);
PAINT SKYBLUE (-7150 3400);
FORCEPROP 1 LAST PATH I76
J 0
(-7350 3550);
DISPLAY 0.978723 (-7350 3550);
PAINT WHITE (-7350 3550);
DISPLAY INVISIBLE (-7350 3550);
FORCEPROP 1 LAST PART_NUMBER CS00002JB13
J 0
(-7400 3475);
DISPLAY 0.510638 (-7400 3475);
PAINT WHITE (-7400 3475);
DISPLAY INVISIBLE (-7400 3475);
FORCEPROP 1 LAST PACK_TYPE 0402LF
J 0
(-7325 3450);
DISPLAY 0.510638 (-7325 3450);
PAINT SKYBLUE (-7325 3450);
DISPLAY INVISIBLE (-7325 3450);
FORCEPROP 1 LAST WATTAGE 1/16W
J 2
(-6950 3500);
DISPLAY 0.510638 (-6950 3500);
PAINT SKYBLUE (-6950 3500);
DISPLAY INVISIBLE (-6950 3500);
FORCEPROP 1 LAST TOLERANCE 5%
J 0
(-7375 3500);
DISPLAY 0.510638 (-7375 3500);
PAINT SKYBLUE (-7375 3500);
DISPLAY INVISIBLE (-7375 3500);
FORCEPROP 2 LAST SEC_TYPE 0402LF
J 0
(-7350 3600);
DISPLAY 0.680851 (-7350 3600);
DISPLAY INVISIBLE (-7350 3600);
FORCEPROP 2 LAST CDS_LIB pure_quanta
J 0
(-7300 3400);
DISPLAY INVISIBLE (-7300 3400);
FORCEPROP 1 LAST LOCATION R574
J 0
(-7575 3400);
DISPLAY 0.702128 (-7575 3400);
PAINT YELLOW (-7575 3400);
FORCEPROP 1 LASTPIN (-7400 3400) $PN 1
J 0
(-7388 3412);
DISPLAY 0.808511 (-7388 3412);
PAINT WHITE (-7388 3412);
FORCEPROP 1 LASTPIN (-7200 3400) $PN 2
J 0
(-7238 3412);
DISPLAY 0.808511 (-7238 3412);
PAINT WHITE (-7238 3412);
FORCEPROP 2 LAST SEC 1
J 0
(-7350 3600);
DISPLAY 0.680851 (-7350 3600);
PAINT MONO (-7350 3600);
DISPLAY INVISIBLE (-7350 3600);
FORCEADD OFFPAGE..6
(-8550 4950);
FORCEPROP 2 LAST $XR0 13 
J 0
(-8829 4950);
DISPLAY 0.638298 (-8829 4950);
PAINT MONO (-8829 4950);
FORCEPROP 2 LAST $XR1 27 
J 0
(-8919 4950);
DISPLAY 0.638298 (-8919 4950);
PAINT MONO (-8919 4950);
FORCEPROP 1 LAST COMMENT_BODY TRUE
J 0
(-8450 4875);
DISPLAY 0.872340 (-8450 4875);
PAINT GREEN (-8450 4875);
DISPLAY INVISIBLE (-8450 4875);
FORCEPROP 1 LAST OFFPAGE TRUE
J 0
(-8225 4825);
DISPLAY 0.872340 (-8225 4825);
DISPLAY INVISIBLE (-8225 4825);
FORCEPROP 2 LAST CDS_LIB standard
J 0
(-8550 4950);
DISPLAY INVISIBLE (-8550 4950);
FORCEPROP 2 LAST PATH I8
J 0
(-8775 5000);
DISPLAY 0.680851 (-8775 5000);
DISPLAY INVISIBLE (-8775 5000);
FORCEADD Q_RES..1
(-7300 4150);
FORCEPROP 1 LAST VALUE 0
J 2
(-7150 4150);
DISPLAY 0.510638 (-7150 4150);
PAINT SKYBLUE (-7150 4150);
FORCEPROP 1 LAST MATERIAL CHIP
J 2
(-6975 4150);
DISPLAY 0.510638 (-6975 4150);
PAINT SKYBLUE (-6975 4150);
FORCEPROP 1 LAST PATH I80
J 0
(-7350 4300);
DISPLAY 0.978723 (-7350 4300);
PAINT WHITE (-7350 4300);
DISPLAY INVISIBLE (-7350 4300);
FORCEPROP 1 LAST PART_NUMBER CS00002JB13
J 0
(-7400 4225);
DISPLAY 0.510638 (-7400 4225);
PAINT WHITE (-7400 4225);
DISPLAY INVISIBLE (-7400 4225);
FORCEPROP 1 LAST PACK_TYPE 0402LF
J 0
(-7325 4200);
DISPLAY 0.510638 (-7325 4200);
PAINT SKYBLUE (-7325 4200);
DISPLAY INVISIBLE (-7325 4200);
FORCEPROP 1 LAST WATTAGE 1/16W
J 2
(-6950 4250);
DISPLAY 0.510638 (-6950 4250);
PAINT SKYBLUE (-6950 4250);
DISPLAY INVISIBLE (-6950 4250);
FORCEPROP 1 LAST TOLERANCE 5%
J 0
(-7375 4250);
DISPLAY 0.510638 (-7375 4250);
PAINT SKYBLUE (-7375 4250);
DISPLAY INVISIBLE (-7375 4250);
FORCEPROP 2 LAST CDS_LIB pure_quanta
J 0
(-7300 4150);
DISPLAY INVISIBLE (-7300 4150);
FORCEPROP 2 LAST SEC_TYPE 0402LF
J 0
(-7350 4350);
DISPLAY 1.021277 (-7350 4350);
DISPLAY INVISIBLE (-7350 4350);
FORCEPROP 1 LAST LOCATION R51
J 0
(-7575 4150);
DISPLAY 0.702128 (-7575 4150);
PAINT YELLOW (-7575 4150);
FORCEPROP 1 LASTPIN (-7400 4150) $PN 1
J 0
(-7388 4162);
DISPLAY 0.808511 (-7388 4162);
PAINT WHITE (-7388 4162);
FORCEPROP 1 LASTPIN (-7200 4150) $PN 2
J 0
(-7238 4162);
DISPLAY 0.808511 (-7238 4162);
PAINT WHITE (-7238 4162);
FORCEPROP 0 LAST SEC 1
J 0
(-7450 4200);
DISPLAY 0.680851 (-7450 4200);
PAINT MONO (-7450 4200);
DISPLAY INVISIBLE (-7450 4200);
FORCEADD OFFPAGE..1
(-8550 4600);
FORCEPROP 2 LAST $XR0 13 
J 0
(-8771 4600);
DISPLAY 0.638298 (-8771 4600);
PAINT MONO (-8771 4600);
FORCEPROP 2 LAST $XR1 22 
J 0
(-8861 4600);
DISPLAY 0.638298 (-8861 4600);
PAINT MONO (-8861 4600);
FORCEPROP 2 LAST PATH I84
J 0
(-8750 4650);
DISPLAY 0.680851 (-8750 4650);
DISPLAY INVISIBLE (-8750 4650);
FORCEPROP 1 LAST COMMENT_BODY TRUE
J 0
(-8425 4500);
DISPLAY 0.872340 (-8425 4500);
PAINT GREEN (-8425 4500);
DISPLAY INVISIBLE (-8425 4500);
FORCEPROP 1 LAST OFFPAGE TRUE
J 0
(-8225 4475);
DISPLAY 0.872340 (-8225 4475);
DISPLAY INVISIBLE (-8225 4475);
FORCEPROP 2 LAST CDS_LIB standard
J 0
(-8550 4600);
DISPLAY INVISIBLE (-8550 4600);
FORCEADD OFFPAGE..5
(-8550 4500);
FORCEPROP 2 LAST $XR0 13 
J 0
(-8774 4500);
DISPLAY 0.638298 (-8774 4500);
PAINT MONO (-8774 4500);
FORCEPROP 2 LAST $XR1 28 
J 0
(-8864 4500);
DISPLAY 0.638298 (-8864 4500);
PAINT MONO (-8864 4500);
FORCEPROP 2 LAST CDS_LIB standard
J 0
(-8550 4500);
DISPLAY INVISIBLE (-8550 4500);
FORCEPROP 2 LAST PATH I85
J 0
(-8800 4550);
DISPLAY 0.680851 (-8800 4550);
DISPLAY INVISIBLE (-8800 4550);
FORCEPROP 1 LAST COMMENT_BODY TRUE
J 0
(-8450 4425);
DISPLAY 0.872340 (-8450 4425);
PAINT PEACH (-8450 4425);
DISPLAY INVISIBLE (-8450 4425);
FORCEPROP 1 LAST OFFPAGE TRUE
J 0
(-8225 4375);
DISPLAY 0.872340 (-8225 4375);
PAINT GREEN (-8225 4375);
DISPLAY INVISIBLE (-8225 4375);
FORCEADD Q_RES..1
(-7300 4600);
FORCEPROP 1 LAST MATERIAL CHIP
J 2
(-6975 4600);
DISPLAY 0.510638 (-6975 4600);
PAINT SKYBLUE (-6975 4600);
FORCEPROP 1 LAST VALUE 0
J 2
(-7150 4600);
DISPLAY 0.510638 (-7150 4600);
PAINT SKYBLUE (-7150 4600);
FORCEPROP 2 LAST SEC_TYPE 0402LF
J 0
(-7350 4800);
DISPLAY 0.680851 (-7350 4800);
DISPLAY INVISIBLE (-7350 4800);
FORCEPROP 2 LAST CDS_LIB pure_quanta
J 0
(-7300 4600);
DISPLAY INVISIBLE (-7300 4600);
FORCEPROP 1 LAST TOLERANCE 5%
J 0
(-7375 4700);
DISPLAY 0.510638 (-7375 4700);
PAINT SKYBLUE (-7375 4700);
DISPLAY INVISIBLE (-7375 4700);
FORCEPROP 1 LAST WATTAGE 1/16W
J 2
(-6950 4700);
DISPLAY 0.510638 (-6950 4700);
PAINT SKYBLUE (-6950 4700);
DISPLAY INVISIBLE (-6950 4700);
FORCEPROP 1 LAST PACK_TYPE 0402LF
J 0
(-7325 4650);
DISPLAY 0.510638 (-7325 4650);
PAINT SKYBLUE (-7325 4650);
DISPLAY INVISIBLE (-7325 4650);
FORCEPROP 1 LAST PART_NUMBER CS00002JB13
J 0
(-7400 4675);
DISPLAY 0.510638 (-7400 4675);
PAINT WHITE (-7400 4675);
DISPLAY INVISIBLE (-7400 4675);
FORCEPROP 1 LAST PATH I88
J 0
(-7350 4750);
DISPLAY 0.978723 (-7350 4750);
PAINT WHITE (-7350 4750);
DISPLAY INVISIBLE (-7350 4750);
FORCEPROP 1 LAST LOCATION R271
J 0
(-7575 4600);
DISPLAY 0.702128 (-7575 4600);
PAINT YELLOW (-7575 4600);
FORCEPROP 1 LASTPIN (-7400 4600) $PN 1
J 0
(-7388 4612);
DISPLAY 0.808511 (-7388 4612);
PAINT WHITE (-7388 4612);
FORCEPROP 1 LASTPIN (-7200 4600) $PN 2
J 0
(-7238 4612);
DISPLAY 0.808511 (-7238 4612);
PAINT WHITE (-7238 4612);
FORCEPROP 2 LAST SEC 1
J 0
(-7350 4800);
DISPLAY 0.680851 (-7350 4800);
PAINT MONO (-7350 4800);
DISPLAY INVISIBLE (-7350 4800);
FORCEADD OFFPAGE..5
(-7150 4675);
FORCEPROP 2 LAST $XR0 42 
J 0
(-7404 4675);
DISPLAY 0.638298 (-7404 4675);
PAINT MONO (-7404 4675);
FORCEPROP 2 LAST PATH I89
J 0
(-7400 4725);
DISPLAY 0.680851 (-7400 4725);
DISPLAY INVISIBLE (-7400 4725);
FORCEPROP 1 LAST COMMENT_BODY TRUE
J 0
(-7050 4600);
DISPLAY 0.872340 (-7050 4600);
PAINT PEACH (-7050 4600);
DISPLAY INVISIBLE (-7050 4600);
FORCEPROP 1 LAST OFFPAGE TRUE
J 0
(-6825 4550);
DISPLAY 0.872340 (-6825 4550);
PAINT GREEN (-6825 4550);
DISPLAY INVISIBLE (-6825 4550);
FORCEPROP 2 LAST CDS_LIB standard
J 0
(-7150 4675);
DISPLAY INVISIBLE (-7150 4675);
FORCEADD OFFPAGE..6
(-8550 4900);
FORCEPROP 2 LAST $XR0 13 
J 0
(-8829 4900);
DISPLAY 0.638298 (-8829 4900);
PAINT MONO (-8829 4900);
FORCEPROP 2 LAST $XR1 27 
J 0
(-8919 4900);
DISPLAY 0.638298 (-8919 4900);
PAINT MONO (-8919 4900);
FORCEPROP 1 LAST COMMENT_BODY TRUE
J 0
(-8450 4825);
DISPLAY 0.872340 (-8450 4825);
PAINT GREEN (-8450 4825);
DISPLAY INVISIBLE (-8450 4825);
FORCEPROP 1 LAST OFFPAGE TRUE
J 0
(-8225 4775);
DISPLAY 0.872340 (-8225 4775);
DISPLAY INVISIBLE (-8225 4775);
FORCEPROP 2 LAST CDS_LIB standard
J 0
(-8550 4900);
DISPLAY INVISIBLE (-8550 4900);
FORCEPROP 2 LAST PATH I9
J 0
(-8775 4950);
DISPLAY 0.680851 (-8775 4950);
DISPLAY INVISIBLE (-8775 4950);
FORCEADD Q_RES..1
(-1800 3050);
FORCEPROP 1 LAST VALUE 0
J 2
(-1650 3050);
DISPLAY 0.510638 (-1650 3050);
PAINT SKYBLUE (-1650 3050);
FORCEPROP 1 LAST MATERIAL CHIP
J 2
(-1475 3050);
DISPLAY 0.510638 (-1475 3050);
PAINT SKYBLUE (-1475 3050);
FORCEPROP 1 LAST PATH I95
J 0
(-1850 3200);
DISPLAY 0.978723 (-1850 3200);
PAINT WHITE (-1850 3200);
DISPLAY INVISIBLE (-1850 3200);
FORCEPROP 2 LAST SEC_TYPE 0402LF
J 0
(-1850 3250);
DISPLAY 0.680851 (-1850 3250);
DISPLAY INVISIBLE (-1850 3250);
FORCEPROP 2 LAST CDS_LIB pure_quanta
J 0
(-1800 3050);
DISPLAY INVISIBLE (-1800 3050);
FORCEPROP 1 LAST TOLERANCE 5%
J 0
(-1875 3150);
DISPLAY 0.510638 (-1875 3150);
PAINT SKYBLUE (-1875 3150);
DISPLAY INVISIBLE (-1875 3150);
FORCEPROP 1 LAST WATTAGE 1/16W
J 2
(-1450 3150);
DISPLAY 0.510638 (-1450 3150);
PAINT SKYBLUE (-1450 3150);
DISPLAY INVISIBLE (-1450 3150);
FORCEPROP 1 LAST PACK_TYPE 0402LF
J 0
(-1825 3100);
DISPLAY 0.510638 (-1825 3100);
PAINT SKYBLUE (-1825 3100);
DISPLAY INVISIBLE (-1825 3100);
FORCEPROP 1 LAST PART_NUMBER CS00002JB13
J 0
(-1900 3125);
DISPLAY 0.510638 (-1900 3125);
PAINT WHITE (-1900 3125);
DISPLAY INVISIBLE (-1900 3125);
FORCEPROP 1 LAST LOCATION R320
J 0
(-2075 3050);
DISPLAY 0.702128 (-2075 3050);
PAINT YELLOW (-2075 3050);
FORCEPROP 1 LASTPIN (-1900 3050) $PN 1
J 0
(-1888 3062);
DISPLAY 0.808511 (-1888 3062);
PAINT WHITE (-1888 3062);
FORCEPROP 1 LASTPIN (-1700 3050) $PN 2
J 0
(-1738 3062);
DISPLAY 0.808511 (-1738 3062);
PAINT WHITE (-1738 3062);
FORCEPROP 0 LAST SEC 1
J 0
(-1950 3100);
DISPLAY 0.680851 (-1950 3100);
PAINT MONO (-1950 3100);
DISPLAY INVISIBLE (-1950 3100);
FORCEADD Q_RES..1
(-1800 3100);
FORCEPROP 1 LAST MATERIAL CHIP
J 2
(-1475 3100);
DISPLAY 0.510638 (-1475 3100);
PAINT SKYBLUE (-1475 3100);
FORCEPROP 1 LAST VALUE 0
J 2
(-1650 3100);
DISPLAY 0.510638 (-1650 3100);
PAINT SKYBLUE (-1650 3100);
FORCEPROP 1 LAST PATH I98
J 0
(-1850 3250);
DISPLAY 0.978723 (-1850 3250);
PAINT WHITE (-1850 3250);
DISPLAY INVISIBLE (-1850 3250);
FORCEPROP 2 LAST SEC_TYPE 0402LF
J 0
(-1850 3300);
DISPLAY 0.680851 (-1850 3300);
DISPLAY INVISIBLE (-1850 3300);
FORCEPROP 2 LAST CDS_LIB pure_quanta
J 0
(-1800 3100);
DISPLAY INVISIBLE (-1800 3100);
FORCEPROP 1 LAST TOLERANCE 5%
J 0
(-1875 3200);
DISPLAY 0.510638 (-1875 3200);
PAINT SKYBLUE (-1875 3200);
DISPLAY INVISIBLE (-1875 3200);
FORCEPROP 1 LAST WATTAGE 1/16W
J 2
(-1450 3200);
DISPLAY 0.510638 (-1450 3200);
PAINT SKYBLUE (-1450 3200);
DISPLAY INVISIBLE (-1450 3200);
FORCEPROP 1 LAST PACK_TYPE 0402LF
J 0
(-1825 3150);
DISPLAY 0.510638 (-1825 3150);
PAINT SKYBLUE (-1825 3150);
DISPLAY INVISIBLE (-1825 3150);
FORCEPROP 1 LAST PART_NUMBER CS00002JB13
J 0
(-1900 3175);
DISPLAY 0.510638 (-1900 3175);
PAINT WHITE (-1900 3175);
DISPLAY INVISIBLE (-1900 3175);
FORCEPROP 1 LAST LOCATION R318
J 0
(-2075 3100);
DISPLAY 0.702128 (-2075 3100);
PAINT YELLOW (-2075 3100);
FORCEPROP 1 LASTPIN (-1900 3100) $PN 1
J 0
(-1888 3112);
DISPLAY 0.808511 (-1888 3112);
PAINT WHITE (-1888 3112);
FORCEPROP 1 LASTPIN (-1700 3100) $PN 2
J 0
(-1738 3112);
DISPLAY 0.808511 (-1738 3112);
PAINT WHITE (-1738 3112);
FORCEPROP 0 LAST SEC 1
J 0
(-1950 3150);
DISPLAY 0.680851 (-1950 3150);
PAINT MONO (-1950 3150);
DISPLAY INVISIBLE (-1950 3150);
FORCEADD Q_RES..1
(-2750 3250);
FORCEPROP 1 LAST MATERIAL CHIP
J 2
(-2425 3250);
DISPLAY 0.510638 (-2425 3250);
PAINT SKYBLUE (-2425 3250);
FORCEPROP 1 LAST VALUE 0
J 2
(-2600 3250);
DISPLAY 0.510638 (-2600 3250);
PAINT SKYBLUE (-2600 3250);
FORCEPROP 1 LAST PART_NUMBER CS00002JB13
J 0
(-2850 3325);
DISPLAY 0.510638 (-2850 3325);
PAINT WHITE (-2850 3325);
DISPLAY INVISIBLE (-2850 3325);
FORCEPROP 1 LAST PACK_TYPE 0402LF
J 0
(-2775 3300);
DISPLAY 0.510638 (-2775 3300);
PAINT SKYBLUE (-2775 3300);
DISPLAY INVISIBLE (-2775 3300);
FORCEPROP 1 LAST WATTAGE 1/16W
J 2
(-2400 3350);
DISPLAY 0.510638 (-2400 3350);
PAINT SKYBLUE (-2400 3350);
DISPLAY INVISIBLE (-2400 3350);
FORCEPROP 1 LAST TOLERANCE 5%
J 0
(-2825 3350);
DISPLAY 0.510638 (-2825 3350);
PAINT SKYBLUE (-2825 3350);
DISPLAY INVISIBLE (-2825 3350);
FORCEPROP 2 LAST CDS_LIB pure_quanta
J 0
(-2750 3250);
DISPLAY INVISIBLE (-2750 3250);
FORCEPROP 2 LAST SEC_TYPE 0402LF
J 0
(-2800 3450);
DISPLAY 0.680851 (-2800 3450);
DISPLAY INVISIBLE (-2800 3450);
FORCEPROP 1 LAST PATH I99
J 0
(-2800 3400);
DISPLAY 0.978723 (-2800 3400);
PAINT WHITE (-2800 3400);
DISPLAY INVISIBLE (-2800 3400);
FORCEPROP 1 LAST LOCATION R317
J 0
(-3025 3250);
DISPLAY 0.702128 (-3025 3250);
PAINT YELLOW (-3025 3250);
FORCEPROP 1 LASTPIN (-2850 3250) $PN 1
J 0
(-2835 3260);
DISPLAY 0.808511 (-2835 3260);
PAINT WHITE (-2835 3260);
FORCEPROP 1 LASTPIN (-2650 3250) $PN 2
J 0
(-2685 3260);
DISPLAY 0.808511 (-2685 3260);
PAINT WHITE (-2685 3260);
FORCEPROP 0 LAST SEC 1
J 0
(-2900 3300);
DISPLAY 0.680851 (-2900 3300);
PAINT MONO (-2900 3300);
DISPLAY INVISIBLE (-2900 3300);
FORCEADD QUANTA_TITLE_BLOCK_C..1
(0 0);
FORCEPROP 0 LAST CDS_CON_LAST_MODIFIED Fri Aug 25 17:25:44 2023
J 0
(-1885 15);
DISPLAY INVISIBLE (-1885 15);
FORCEPROP 2 LAST Q_DEPT 
J 1
(-3763 49);
DISPLAY 1.957447 (-3763 49);
PAINT GREEN (-3763 49);
FORCEPROP 1 LAST CUSTOM_TXT_CDS <CON_LAST_MODIFIED>
J 0
(-1885 15);
DISPLAY 0.978723 (-1885 15);
FORCEPROP 2 LAST CUSTOM_TXT_CDS <XR_PAGE_TITLE>
J 0
(-7890 5250);
DISPLAY 0.638298 (-7890 5250);
PAINT PINK (-7890 5250);
DISPLAY INVISIBLE (-7890 5250);
FORCEPROP 1 LAST CUSTOM_TXT_CDS <NAME_2>
J 0
(-3175 50);
FORCEPROP 1 LAST CUSTOM_TXT_CDS <NAME_1>
J 0
(-3175 175);
FORCEPROP 1 LAST CUSTOM_TXT_CDS <Q_NUMBER>
J 0
(-1403 103);
DISPLAY 1.212766 (-1403 103);
FORCEPROP 1 LAST CUSTOM_TXT_CDS <Q_PROJ>
J 0
(-2382 102);
DISPLAY 1.212766 (-2382 102);
FORCEPROP 1 LAST CUSTOM_TXT_CDS <Q_REV>
J 0
(-184 103);
DISPLAY 1.212766 (-184 103);
FORCEPROP 1 LAST CUSTOM_TXT_CDS <CON_PAGE_NUM> OF <CON_TOTAL_PAGES>
J 0
(-446 18);
DISPLAY 0.978723 (-446 18);
FORCEPROP 1 LAST Q_TITLE FPGA 2/8
J 0
(-9366 26);
DISPLAY 2.446809 (-9366 26);
PAINT GREEN (-9366 26);
FORCEPROP 2 LAST CDS_LIB pure_quanta
J 0
(0 0);
DISPLAY INVISIBLE (0 0);
FORCEPROP 1 LAST COMMENT_BODY TRUE
J 0
(12 -13);
DISPLAY 0.978723 (12 -13);
PAINT GREEN (12 -13);
DISPLAY INVISIBLE (12 -13);
FORCEPROP 1 LAST CDS_LMAN_SYM_OUTLINE -9475,6775,100,-125
J 0
(0 0);
DISPLAY 0.468085 (0 0);
PAINT GREEN (0 0);
DISPLAY INVISIBLE (0 0);
FORCEPROP 2 LAST PAGE_BORDER TRUE
J 0
(-7890 5250);
DISPLAY 0.638298 (-7890 5250);
PAINT PINK (-7890 5250);
DISPLAY INVISIBLE (-7890 5250);
FORCEPROP 2 LAST CDS_XR_PAGE_TITLE CR-35 : @SCM_LIB.SCM(SCH_1):PAGE35
J 0
(-7890 5250);
DISPLAY 0.638298 (-7890 5250);
PAINT PINK (-7890 5250);
DISPLAY INVISIBLE (-7890 5250);
FORCEADD DNS..1
(-1850 3200);
PAINT RED (-1850 3200);
FORCEPROP 1 LAST COMMENT_BODY TRUE
R 1
J 0
(-1775 2975);
DISPLAY 0.872340 (-1775 2975);
PAINT PEACH (-1775 2975);
DISPLAY INVISIBLE (-1775 2975);
FORCEPROP 2 LAST CDS_LIB mstr_misc
J 0
(-1850 3200);
DISPLAY INVISIBLE (-1850 3200);
FORCEADD DNS..1
(-2225 4650);
PAINT RED (-2225 4650);
FORCEPROP 2 LAST CDS_LIB mstr_misc
J 0
(-2225 4650);
DISPLAY INVISIBLE (-2225 4650);
FORCEPROP 1 LAST COMMENT_BODY TRUE
R 1
J 0
(-2150 4425);
DISPLAY 0.872340 (-2150 4425);
PAINT PEACH (-2150 4425);
DISPLAY INVISIBLE (-2150 4425);
FORCEADD DNS..2
(-7925 2075);
PAINT RED (-7925 2075);
FORCEPROP 2 LAST CDS_LIB mstr_misc
J 0
(-7925 2075);
DISPLAY INVISIBLE (-7925 2075);
FORCEPROP 1 LAST COMMENT_BODY TRUE
R 1
J 0
(-7850 1850);
DISPLAY 0.872340 (-7850 1850);
PAINT PEACH (-7850 1850);
DISPLAY INVISIBLE (-7850 1850);
FORCEADD DNS..1
(-6775 3600);
PAINT RED (-6775 3600);
FORCEPROP 2 LAST CDS_LIB mstr_misc
J 0
(-6775 3600);
DISPLAY INVISIBLE (-6775 3600);
FORCEPROP 1 LAST COMMENT_BODY TRUE
R 1
J 0
(-6700 3375);
DISPLAY 0.872340 (-6700 3375);
PAINT PEACH (-6700 3375);
DISPLAY INVISIBLE (-6700 3375);
FORCEADD DNS..1
(-2225 4750);
PAINT RED (-2225 4750);
FORCEPROP 2 LAST CDS_LIB mstr_misc
J 0
(-2225 4750);
DISPLAY INVISIBLE (-2225 4750);
FORCEPROP 1 LAST COMMENT_BODY TRUE
R 1
J 0
(-2150 4525);
DISPLAY 0.872340 (-2150 4525);
PAINT PEACH (-2150 4525);
DISPLAY INVISIBLE (-2150 4525);
WIRE 16 -1 (-6000 2700)(-6000 2650);
WIRE 16 -1 (-8525 2375)(-8525 2075);
WIRE 16 -1 (-3500 2700)(-3500 2650);
WIRE 16 -1 (-3175 1775)(-3175 1850);
WIRE 16 -1 (-3050 1775)(-3175 1775);
WIRE 16 -1 (-6000 2650)(-5825 2650);
WIRE 16 -1 (-5825 2650)(-5625 2650);
WIRE 16 -1 (-5825 2600)(-5825 2650);
WIRE 16 -1 (-5825 2600)(-5625 2600);
WIRE 16 -1 (-3675 2650)(-3875 2650);
WIRE 16 -1 (-3500 2650)(-3675 2650);
WIRE 16 -1 (-3675 2600)(-3675 2650);
WIRE 16 -1 (-3875 2600)(-3675 2600);
WIRE 16 -1 (-3875 4300)(-2350 4300);
FORCEPROP 2 LAST SIG_NAME BMC_CPLD_GPIO_13_R2
J 2
(-3010 4310);
DISPLAY 0.808511 (-3010 4310);
WIRE 16 -1 (-3875 4000)(-1900 4000);
FORCEPROP 2 LAST SIG_NAME RST_BMC_HW_R
J 0
(-3685 4010);
DISPLAY 0.851064 (-3685 4010);
WIRE 16 -1 (-3875 3850)(-1900 3850);
FORCEPROP 2 LAST SIG_NAME FM_PWR_R_BTN
J 2
(-3235 3860);
DISPLAY 0.808511 (-3235 3860);
WIRE 16 -1 (-3875 3800)(-1900 3800);
FORCEPROP 2 LAST SIG_NAME PWRGD_SYS_PWROK_PLD
J 2
(-2960 3810);
DISPLAY 0.808511 (-2960 3810);
WIRE 16 -1 (-3875 3700)(-800 3700);
FORCEPROP 2 LAST SIG_NAME USB_OC0_REAR_R_N
J 2
(-800 3710);
DISPLAY 0.808511 (-800 3710);
WIRE 16 -1 (-800 3650)(-3875 3650);
FORCEPROP 2 LAST SIG_NAME SMB_BMC_ALERT12_N
J 2
(-775 3660);
DISPLAY 0.808511 (-775 3660);
WIRE 16 -1 (-3875 3550)(-800 3550);
FORCEPROP 2 LAST SIG_NAME FM_BMC_READY_PLD_N
J 0
(-1635 3560);
DISPLAY 0.851064 (-1635 3560);
WIRE 16 -1 (-3875 3500)(-800 3500);
FORCEPROP 2 LAST SIG_NAME FM_BIOS_DEBUG_EN_N
J 0
(-1635 3510);
DISPLAY 0.851064 (-1635 3510);
WIRE 16 3135 (-2175 3150)(-1600 3150);
WIRE 16 3135 (-1600 3150)(-1600 3475);
WIRE 16 3135 (-2175 3150)(-2175 3475);
WIRE 16 3135 (-2175 3475)(-1600 3475);
WIRE 16 -1 (-2650 3250)(-800 3250);
FORCEPROP 2 LAST SIG_NAME PWR_LED
J 0
(-1410 3260);
DISPLAY 0.808511 (-1410 3260);
WIRE 16 -1 (-1700 3800)(-800 3800);
FORCEPROP 2 LAST SIG_NAME PWRGD_SYS_PWROK
J 2
(-800 3810);
DISPLAY 0.808511 (-800 3810);
WIRE 16 -1 (-1700 3200)(-800 3200);
FORCEPROP 2 LAST SIG_NAME PWRGD_P5V_AUX
J 0
(-1410 3210);
DISPLAY 0.851064 (-1410 3210);
WIRE 16 -1 (-2150 3350)(-2275 3350);
WIRE 16 -1 (-2150 3200)(-2150 3350);
WIRE 16 -1 (-1950 3200)(-2150 3200);
WIRE 16 -1 (-3875 3200)(-2150 3200);
FORCEPROP 2 LAST SIG_NAME PWRGD_P5V_AUX_R1
J 0
(-3685 3210);
DISPLAY 0.851064 (-3685 3210);
WIRE 16 -1 (-3875 3100)(-1900 3100);
FORCEPROP 2 LAST SIG_NAME PWRGD_P3V3_AUX_R1
J 0
(-3685 3110);
DISPLAY 0.851064 (-3685 3110);
WIRE 16 -1 (-3875 3050)(-1900 3050);
FORCEPROP 2 LAST SIG_NAME PWRGD_P2V5_AUX_R1
J 0
(-3685 3060);
DISPLAY 0.851064 (-3685 3060);
WIRE 16 -1 (-7200 4450)(-5625 4450);
FORCEPROP 2 LAST SIG_NAME RST_ROT_CPU_R_N
J 0
(-6910 4460);
DISPLAY 0.851064 (-6910 4460);
WIRE 16 -1 (-7200 4500)(-5625 4500);
FORCEPROP 2 LAST SIG_NAME FM_SLPS3_GF_R_N
J 0
(-6910 4510);
DISPLAY 0.808511 (-6910 4510);
WIRE 16 -1 (-7400 4500)(-8500 4500);
FORCEPROP 2 LAST SIG_NAME FM_SLPS3_GF_N
J 0
(-8500 4510);
DISPLAY 0.808511 (-8500 4510);
WIRE 16 -1 (-8050 2075)(-8525 2075);
WIRE 16 -1 (-8500 3850)(-5625 3850);
FORCEPROP 2 LAST SIG_NAME FM_BMC_EN_DET_R
J 0
(-8500 3860);
DISPLAY 0.808511 (-8500 3860);
WIRE 16 -1 (-8500 3750)(-5625 3750);
FORCEPROP 2 LAST SIG_NAME FM_PCHHOT_R_N
J 0
(-8500 3760);
DISPLAY 0.808511 (-8500 3760);
WIRE 16 -1 (-5625 3700)(-8500 3700);
FORCEPROP 2 LAST SIG_NAME FM_BMC_ONCTL_R_N
J 0
(-8500 3710);
DISPLAY 0.808511 (-8500 3710);
WIRE 16 -1 (-5625 3400)(-7200 3400);
FORCEPROP 2 LAST SIG_NAME SMB_BMC_ALERT16_R2_N
J 0
(-6910 3410);
DISPLAY 0.808511 (-6910 3410);
WIRE 16 -1 (-2850 1775)(-1950 1775);
FORCEPROP 2 LAST SIG_NAME PWRGD_P5V_AUX_R1
J 0
(-2585 1785);
DISPLAY 0.851064 (-2585 1785);
WIRE 16 -1 (-3875 3250)(-2850 3250);
FORCEPROP 2 LAST SIG_NAME PWR_LED_CPLD
J 0
(-3685 3260);
DISPLAY 0.808511 (-3685 3260);
WIRE 16 -1 (-1700 3050)(-800 3050);
FORCEPROP 2 LAST SIG_NAME PWRGD_P2V5_AUX
J 0
(-1410 3060);
DISPLAY 0.851064 (-1410 3060);
WIRE 16 -1 (-1700 3100)(-800 3100);
FORCEPROP 2 LAST SIG_NAME PWRGD_P3V3_AUX
J 0
(-1410 3110);
DISPLAY 0.851064 (-1410 3110);
WIRE 16 -1 (-6125 4675)(-7100 4675);
WIRE 16 -1 (-6125 4600)(-7200 4600);
FORCEPROP 2 LAST SIG_NAME RST_BMC_SELF_HW_R2
J 0
(-6910 4610);
DISPLAY 0.851064 (-6910 4610);
WIRE 16 -1 (-5625 4600)(-6125 4600);
WIRE 16 -1 (-6125 4600)(-6125 4675);
WIRE 16 -1 (-8500 4600)(-7400 4600);
FORCEPROP 2 LAST SIG_NAME RST_BMC_SELF_HW
J 0
(-8510 4610);
DISPLAY 0.851064 (-8510 4610);
WIRE 16 -1 (-5625 4650)(-6100 4650);
FORCEPROP 2 LAST SIG_NAME TP_PLD_L3
J 0
(-6085 4660);
DISPLAY 0.808511 (-6085 4660);
WIRE 16 -1 (-5625 4750)(-7200 4750);
FORCEPROP 2 LAST SIG_NAME SMB_BMC_ALERT10_R1_N
J 0
(-6910 4760);
DISPLAY 0.808511 (-6910 4760);
WIRE 16 -1 (-5625 4800)(-7200 4800);
FORCEPROP 2 LAST SIG_NAME SMB_BMC_ALERT9_R1_N
J 0
(-6910 4810);
DISPLAY 0.808511 (-6910 4810);
WIRE 16 -1 (-5625 4900)(-7200 4900);
FORCEPROP 2 LAST SIG_NAME SMB_BMC_ALERT4_R1_N
J 0
(-6910 4910);
DISPLAY 0.808511 (-6910 4910);
WIRE 16 -1 (-5625 4950)(-7200 4950);
FORCEPROP 2 LAST SIG_NAME SMB_BMC_ALERT3_R1_N
J 0
(-6910 4960);
DISPLAY 0.808511 (-6910 4960);
WIRE 16 -1 (-8500 5050)(-5625 5050);
FORCEPROP 2 LAST SIG_NAME FM_PECI_SEL_N
J 0
(-8485 5060);
DISPLAY 0.851064 (-8485 5060);
WIRE 16 -1 (-8500 5100)(-5625 5100);
FORCEPROP 2 LAST SIG_NAME VOL_SEN_ALERT_R
J 0
(-8500 5110);
DISPLAY 0.808511 (-8500 5110);
WIRE 16 -1 (-5625 4350)(-7200 4350);
FORCEPROP 2 LAST SIG_NAME FM_ESPI_PLD_R_EN
J 0
(-6910 4360);
DISPLAY 0.808511 (-6910 4360);
PAINT YELLOW (-6910 4360);
WIRE 16 -1 (-5625 4300)(-7200 4300);
FORCEPROP 2 LAST SIG_NAME FM_THROTTLE_R_N
J 0
(-6910 4310);
DISPLAY 0.808511 (-6910 4310);
WIRE 16 -1 (-8500 4200)(-5625 4200);
FORCEPROP 2 LAST SIG_NAME FM_PMBUS_ALERT_EN
J 0
(-8500 4210);
DISPLAY 0.808511 (-8500 4210);
WIRE 16 -1 (-5625 4150)(-7200 4150);
FORCEPROP 2 LAST SIG_NAME H_CPU0_PROCHOT_LVC1_R_N
J 0
(-6910 4160);
DISPLAY 0.808511 (-6910 4160);
WIRE 16 -1 (-5625 4050)(-7200 4050);
FORCEPROP 2 LAST SIG_NAME RST_MB_STBY_R_N
J 0
(-6910 4060);
DISPLAY 0.808511 (-6910 4060);
WIRE 16 -1 (-8500 4000)(-5625 4000);
FORCEPROP 2 LAST SIG_NAME FM_ADR_TRIGGER_N
J 0
(-8500 4010);
DISPLAY 0.808511 (-8500 4010);
WIRE 16 -1 (-5625 3600)(-6700 3600);
FORCEPROP 2 LAST SIG_NAME AC_PWR_BTN_R2_N
J 0
(-6410 3610);
DISPLAY 0.851064 (-6410 3610);
WIRE 16 -1 (-6750 2075)(-7850 2075);
FORCEPROP 2 LAST SIG_NAME AC_PWR_BTN_R1_N
J 0
(-7410 2085);
DISPLAY 0.851064 (-7410 2085);
WIRE 16 -1 (-1700 3850)(-800 3850);
FORCEPROP 2 LAST SIG_NAME FM_PWR_BTN
J 2
(-800 3860);
DISPLAY 0.808511 (-800 3860);
WIRE 16 -1 (-8500 3400)(-7400 3400);
FORCEPROP 2 LAST SIG_NAME SMB_BMC_ALERT16_N
J 0
(-8510 3410);
DISPLAY 0.808511 (-8510 3410);
WIRE 16 -1 (-825 5100)(-3875 5100);
FORCEPROP 2 LAST SIG_NAME H_CPU0_MEMTRIP_LVC1_N
J 2
(-800 5110);
DISPLAY 0.808511 (-800 5110);
WIRE 16 -1 (-825 5050)(-3875 5050);
FORCEPROP 2 LAST SIG_NAME FM_SPD_REMOTE_EN_R
J 2
(-800 5060);
DISPLAY 0.808511 (-800 5060);
WIRE 16 -1 (-825 4950)(-3875 4950);
FORCEPROP 2 LAST SIG_NAME H_CPU1_MEMTRIP_LVC1_N
J 2
(-800 4960);
DISPLAY 0.808511 (-800 4960);
WIRE 16 -1 (-3875 4900)(-2350 4900);
FORCEPROP 2 LAST SIG_NAME IRQ_SGPIO_R_N
J 0
(-3685 4910);
DISPLAY 0.808511 (-3685 4910);
WIRE 16 -1 (-3875 4800)(-2350 4800);
FORCEPROP 2 LAST SIG_NAME RST_SGPIO_RESET_R_N
J 0
(-3685 4810);
DISPLAY 0.808511 (-3685 4810);
WIRE 16 -1 (-3875 4750)(-2350 4750);
FORCEPROP 2 LAST SIG_NAME BMC_CPLD_GPIO_7_R2
J 2
(-3010 4760);
DISPLAY 0.808511 (-3010 4760);
WIRE 16 -1 (-3875 4350)(-2350 4350);
FORCEPROP 2 LAST SIG_NAME BMC_CPLD_GPIO_12_R2
J 2
(-3010 4360);
DISPLAY 0.808511 (-3010 4360);
WIRE 16 -1 (-3875 4650)(-2350 4650);
FORCEPROP 2 LAST SIG_NAME BMC_CPLD_GPIO_8_R2
J 2
(-3010 4660);
DISPLAY 0.808511 (-3010 4660);
WIRE 16 -1 (-2150 4650)(-825 4650);
FORCEPROP 2 LAST SIG_NAME BMC_CPLD_GPIO_8
J 2
(-860 4660);
DISPLAY 0.808511 (-860 4660);
WIRE 16 -1 (-8000 3600)(-6900 3600);
FORCEPROP 2 LAST SIG_NAME AC_PWR_BTN_R1_N
J 0
(-8010 3610);
DISPLAY 0.851064 (-8010 3610);
WIRE 16 -1 (-8500 4450)(-7400 4450);
FORCEPROP 2 LAST SIG_NAME RST_ROT_CPU_N
J 0
(-8510 4460);
DISPLAY 0.851064 (-8510 4460);
WIRE 16 -1 (-1700 4000)(-800 4000);
FORCEPROP 2 LAST SIG_NAME RST_BMC_HW
J 0
(-1385 4010);
DISPLAY 0.851064 (-1385 4010);
WIRE 16 -1 (-7400 4300)(-8500 4300);
FORCEPROP 2 LAST SIG_NAME FM_THROTTLE_N
J 0
(-8500 4310);
DISPLAY 0.808511 (-8500 4310);
WIRE 16 -1 (-8500 4350)(-7400 4350);
FORCEPROP 2 LAST SIG_NAME FM_ESPI_PLD_EN
J 0
(-8500 4360);
DISPLAY 0.808511 (-8500 4360);
PAINT YELLOW (-8500 4360);
WIRE 16 -1 (-8500 4050)(-7400 4050);
FORCEPROP 2 LAST SIG_NAME RST_MB_STBY_N
J 0
(-8510 4060);
DISPLAY 0.808511 (-8510 4060);
WIRE 16 -1 (-8500 4150)(-7400 4150);
FORCEPROP 2 LAST SIG_NAME H_CPU0_PROCHOT_LVC1_N
J 0
(-8500 4160);
DISPLAY 0.808511 (-8500 4160);
WIRE 16 -1 (-2150 4900)(-825 4900);
FORCEPROP 2 LAST SIG_NAME IRQ_SGPIO_N
J 2
(-800 4910);
DISPLAY 0.808511 (-800 4910);
WIRE 16 -1 (-2150 4800)(-825 4800);
FORCEPROP 2 LAST SIG_NAME RST_SGPIO_RESET_N
J 2
(-800 4810);
DISPLAY 0.808511 (-800 4810);
WIRE 16 -1 (-2150 4750)(-825 4750);
FORCEPROP 2 LAST SIG_NAME BMC_CPLD_GPIO_7
J 2
(-860 4760);
DISPLAY 0.808511 (-860 4760);
WIRE 16 -1 (-2150 4300)(-825 4300);
FORCEPROP 2 LAST SIG_NAME BMC_CPLD_GPIO_13
J 2
(-860 4310);
DISPLAY 0.808511 (-860 4310);
WIRE 16 -1 (-2150 4350)(-825 4350);
FORCEPROP 2 LAST SIG_NAME BMC_CPLD_GPIO_12
J 2
(-860 4360);
DISPLAY 0.808511 (-860 4360);
WIRE 16 -1 (-8500 4800)(-7400 4800);
FORCEPROP 2 LAST SIG_NAME SMB_BMC_ALERT9_N
J 0
(-8485 4810);
DISPLAY 0.808511 (-8485 4810);
WIRE 16 -1 (-8500 4750)(-7400 4750);
FORCEPROP 2 LAST SIG_NAME SMB_BMC_ALERT10_N
J 0
(-8485 4760);
DISPLAY 0.808511 (-8485 4760);
WIRE 16 -1 (-8500 4900)(-7400 4900);
FORCEPROP 2 LAST SIG_NAME SMB_BMC_ALERT4_N
J 0
(-8485 4910);
DISPLAY 0.808511 (-8485 4910);
WIRE 16 -1 (-8500 4950)(-7400 4950);
FORCEPROP 2 LAST SIG_NAME SMB_BMC_ALERT3_N
J 0
(-8485 4960);
DISPLAY 0.808511 (-8485 4960);
DOT 1 (-2150 3200);
DOT 1 (-6125 4600);
DOT 1 (-3675 2650);
DOT 1 (-5825 2650);
FORCENOTE
ADD_20221206
(-1575 3425) 0;
DISPLAY LEFT (-1575 3425);
DISPLAY 1.021277 (-1575 3425);
PAINT WHITE (-1575 3425);
QUIT
